FILE_TYPE = MACRO_DRAWING;
SET COLOR_WIRE YELLOW;
SET COLOR_PROP MONO;
SET COLOR_DOT WHITE;
SET COLOR_ARC YELLOW;
SET COLOR_BODY GREEN;
SET COLOR_NOTE MONO;
SET PROP_DISPLAY VALUE;
SET PAGE_NUMBER P31;
FORCEADD TAP..1
R 2
(-5450 1950);
FORCEPROP 3 LASTPIN (-5400 1950) SIG_NAME P3E_CPU0_PE2_SS_RXP<1>
J 0
(-5390 1960);
DISPLAY 0.659574 (-5390 1960);
PAINT MONO (-5390 1960);
DISPLAY INVISIBLE (-5390 1960);
FORCEPROP 1 LASTPIN (-5400 1950) BN 1
J 2
(-5388 1958);
DISPLAY 0.617021 (-5388 1958);
PAINT PINK (-5388 1958);
FORCEPROP 2 LAST CDS_LIB mstr_standard
J 0
(-5450 1950);
PAINT MONO (-5450 1950);
DISPLAY INVISIBLE (-5450 1950);
FORCEPROP 1 LAST BODY_TYPE PLUMBING
J 2
(-5450 2000);
DISPLAY 1.446809 (-5450 2000);
PAINT GREEN (-5450 2000);
DISPLAY INVISIBLE (-5450 2000);
FORCEPROP 1 LAST HDL_TAP TRUE
J 2
(-5775 1825);
DISPLAY 1.446809 (-5775 1825);
PAINT GREEN (-5775 1825);
DISPLAY INVISIBLE (-5775 1825);
FORCEPROP 1 LAST PATH I10
J 2
(-5448 1950);
DISPLAY 0.872340 (-5448 1950);
PAINT GREEN (-5448 1950);
DISPLAY INVISIBLE (-5448 1950);
FORCEADD TAP..1
R 2
(-5300 2650);
FORCEPROP 3 LASTPIN (-5250 2650) SIG_NAME P3E_CPU0_PE2_SS_RXN<8>
J 0
(-5240 2660);
DISPLAY 0.659574 (-5240 2660);
PAINT MONO (-5240 2660);
DISPLAY INVISIBLE (-5240 2660);
FORCEPROP 1 LASTPIN (-5250 2650) BN 8
J 2
(-5238 2658);
DISPLAY 0.617021 (-5238 2658);
PAINT PINK (-5238 2658);
FORCEPROP 2 LAST CDS_LIB mstr_standard
J 0
(-5300 2650);
PAINT MONO (-5300 2650);
DISPLAY INVISIBLE (-5300 2650);
FORCEPROP 1 LAST BODY_TYPE PLUMBING
J 2
(-5300 2700);
DISPLAY 1.446809 (-5300 2700);
PAINT GREEN (-5300 2700);
DISPLAY INVISIBLE (-5300 2700);
FORCEPROP 1 LAST HDL_TAP TRUE
J 2
(-5625 2525);
DISPLAY 1.446809 (-5625 2525);
PAINT GREEN (-5625 2525);
DISPLAY INVISIBLE (-5625 2525);
FORCEPROP 1 LAST PATH I100
J 2
(-5298 2650);
DISPLAY 0.872340 (-5298 2650);
PAINT GREEN (-5298 2650);
DISPLAY INVISIBLE (-5298 2650);
FORCEADD TAP..1
R 2
(-5450 3000);
FORCEPROP 3 LASTPIN (-5400 3000) SIG_NAME P3E_CPU0_PE2_SS_RXP<10>
J 0
(-5390 3010);
DISPLAY 0.659574 (-5390 3010);
PAINT MONO (-5390 3010);
DISPLAY INVISIBLE (-5390 3010);
FORCEPROP 1 LASTPIN (-5400 3000) BN 10
J 2
(-5388 3008);
DISPLAY 0.617021 (-5388 3008);
PAINT PINK (-5388 3008);
FORCEPROP 2 LAST CDS_LIB mstr_standard
J 0
(-5450 3000);
PAINT MONO (-5450 3000);
DISPLAY INVISIBLE (-5450 3000);
FORCEPROP 1 LAST BODY_TYPE PLUMBING
J 2
(-5450 3050);
DISPLAY 1.446809 (-5450 3050);
PAINT GREEN (-5450 3050);
DISPLAY INVISIBLE (-5450 3050);
FORCEPROP 1 LAST HDL_TAP TRUE
J 2
(-5775 2875);
DISPLAY 1.446809 (-5775 2875);
PAINT GREEN (-5775 2875);
DISPLAY INVISIBLE (-5775 2875);
FORCEPROP 1 LAST PATH I101
J 2
(-5448 3000);
DISPLAY 0.872340 (-5448 3000);
PAINT GREEN (-5448 3000);
DISPLAY INVISIBLE (-5448 3000);
FORCEADD TAP..1
R 2
(-5450 2950);
FORCEPROP 3 LASTPIN (-5400 2950) SIG_NAME P3E_CPU0_PE2_SS_RXP<9>
J 0
(-5390 2960);
DISPLAY 0.659574 (-5390 2960);
PAINT MONO (-5390 2960);
DISPLAY INVISIBLE (-5390 2960);
FORCEPROP 1 LASTPIN (-5400 2950) BN 9
J 2
(-5388 2958);
DISPLAY 0.617021 (-5388 2958);
PAINT PINK (-5388 2958);
FORCEPROP 2 LAST CDS_LIB mstr_standard
J 0
(-5450 2950);
PAINT MONO (-5450 2950);
DISPLAY INVISIBLE (-5450 2950);
FORCEPROP 1 LAST BODY_TYPE PLUMBING
J 2
(-5450 3000);
DISPLAY 1.446809 (-5450 3000);
PAINT GREEN (-5450 3000);
DISPLAY INVISIBLE (-5450 3000);
FORCEPROP 1 LAST HDL_TAP TRUE
J 2
(-5775 2825);
DISPLAY 1.446809 (-5775 2825);
PAINT GREEN (-5775 2825);
DISPLAY INVISIBLE (-5775 2825);
FORCEPROP 1 LAST PATH I102
J 2
(-5448 2950);
DISPLAY 0.872340 (-5448 2950);
PAINT GREEN (-5448 2950);
DISPLAY INVISIBLE (-5448 2950);
FORCEADD TAP..1
R 2
(-5450 2900);
FORCEPROP 3 LASTPIN (-5400 2900) SIG_NAME P3E_CPU0_PE2_SS_RXP<8>
J 0
(-5390 2910);
DISPLAY 0.659574 (-5390 2910);
PAINT MONO (-5390 2910);
DISPLAY INVISIBLE (-5390 2910);
FORCEPROP 1 LASTPIN (-5400 2900) BN 8
J 2
(-5388 2908);
DISPLAY 0.617021 (-5388 2908);
PAINT PINK (-5388 2908);
FORCEPROP 2 LAST CDS_LIB mstr_standard
J 0
(-5450 2900);
PAINT MONO (-5450 2900);
DISPLAY INVISIBLE (-5450 2900);
FORCEPROP 1 LAST BODY_TYPE PLUMBING
J 2
(-5450 2950);
DISPLAY 1.446809 (-5450 2950);
PAINT GREEN (-5450 2950);
DISPLAY INVISIBLE (-5450 2950);
FORCEPROP 1 LAST HDL_TAP TRUE
J 2
(-5775 2775);
DISPLAY 1.446809 (-5775 2775);
PAINT GREEN (-5775 2775);
DISPLAY INVISIBLE (-5775 2775);
FORCEPROP 1 LAST PATH I103
J 2
(-5448 2900);
DISPLAY 0.872340 (-5448 2900);
PAINT GREEN (-5448 2900);
DISPLAY INVISIBLE (-5448 2900);
FORCEADD OFFPAGE..1
(-6600 3700);
FORCEPROP 2 LAST $XR0 109 
J 0
(-6852 3700);
DISPLAY 0.638298 (-6852 3700);
PAINT MONO (-6852 3700);
FORCEPROP 2 LAST $XR1 245 
J 0
(-6852 3700);
DISPLAY 0.638298 (-6852 3700);
PAINT MONO (-6852 3700);
FORCEPROP 2 LAST CDS_LIB mstr_standard
J 0
(-6600 3700);
PAINT MONO (-6600 3700);
DISPLAY INVISIBLE (-6600 3700);
FORCEPROP 1 LAST OFFPAGE TRUE
J 0
(-6275 3575);
DISPLAY 1.170213 (-6275 3575);
PAINT GREEN (-6275 3575);
DISPLAY INVISIBLE (-6275 3575);
FORCEPROP 1 LAST COMMENT_BODY TRUE
J 0
(-6475 3600);
DISPLAY 1.170213 (-6475 3600);
PAINT GREEN (-6475 3600);
DISPLAY INVISIBLE (-6475 3600);
FORCEPROP 2 LAST PATH I104
J 0
(-6850 3750);
DISPLAY 1.021277 (-6850 3750);
PAINT ORANGE (-6850 3750);
DISPLAY INVISIBLE (-6850 3750);
FORCEADD OFFPAGE..1
(-6600 3650);
FORCEPROP 2 LAST $XR0 109 
J 0
(-6852 3650);
DISPLAY 0.638298 (-6852 3650);
PAINT MONO (-6852 3650);
FORCEPROP 2 LAST $XR1 245 
J 0
(-6852 3650);
DISPLAY 0.638298 (-6852 3650);
PAINT MONO (-6852 3650);
FORCEPROP 2 LAST CDS_LIB mstr_standard
J 0
(-6600 3650);
PAINT MONO (-6600 3650);
DISPLAY INVISIBLE (-6600 3650);
FORCEPROP 1 LAST OFFPAGE TRUE
J 0
(-6275 3525);
DISPLAY 1.170213 (-6275 3525);
PAINT GREEN (-6275 3525);
DISPLAY INVISIBLE (-6275 3525);
FORCEPROP 1 LAST COMMENT_BODY TRUE
J 0
(-6475 3550);
DISPLAY 1.170213 (-6475 3550);
PAINT GREEN (-6475 3550);
DISPLAY INVISIBLE (-6475 3550);
FORCEPROP 2 LAST PATH I105
J 0
(-6850 3700);
DISPLAY 1.021277 (-6850 3700);
PAINT ORANGE (-6850 3700);
DISPLAY INVISIBLE (-6850 3700);
FORCEADD SKX_EXT_B..11
(-4025 2600);
FORCEPROP 1 LAST LOCATION U5D1
J 0
(-4725 3800);
DISPLAY 0.617021 (-4725 3800);
PAINT AQUA (-4725 3800);
FORCEPROP 1 LAST PART_NUMBER TBD
J 0
(-4725 1450);
DISPLAY 0.617021 (-4725 1450);
PAINT BLUE (-4725 1450);
FORCEPROP 1 LAST MATERIAL IC
J 0
(-4725 3750);
DISPLAY 0.617021 (-4725 3750);
PAINT SKYBLUE (-4725 3750);
FORCEPROP 2 LASTPIN (-3275 3550) $PN BK5
J 0
(-3265 3560);
DISPLAY 0.617021 (-3265 3560);
PAINT ORANGE (-3265 3560);
FORCEPROP 2 LASTPIN (-3275 3500) $PN BM3
J 0
(-3265 3510);
DISPLAY 0.617021 (-3265 3510);
PAINT ORANGE (-3265 3510);
FORCEPROP 2 LASTPIN (-3275 3450) $PN BN4
J 0
(-3265 3460);
DISPLAY 0.617021 (-3265 3460);
PAINT ORANGE (-3265 3460);
FORCEPROP 2 LASTPIN (-3275 3400) $PN BR4
J 0
(-3265 3410);
DISPLAY 0.617021 (-3265 3410);
PAINT ORANGE (-3265 3410);
FORCEPROP 2 LASTPIN (-3275 3050) $PN BV3
J 0
(-3265 3060);
DISPLAY 0.617021 (-3265 3060);
PAINT ORANGE (-3265 3060);
FORCEPROP 2 LASTPIN (-3275 3000) $PN BY5
J 0
(-3265 3010);
DISPLAY 0.617021 (-3265 3010);
PAINT ORANGE (-3265 3010);
FORCEPROP 2 LASTPIN (-3275 2950) $PN BY3
J 0
(-3265 2960);
DISPLAY 0.617021 (-3265 2960);
PAINT ORANGE (-3265 2960);
FORCEPROP 2 LASTPIN (-3275 2900) $PN CD3
J 0
(-3265 2910);
DISPLAY 0.617021 (-3265 2910);
PAINT ORANGE (-3265 2910);
FORCEPROP 2 LASTPIN (-3275 2550) $PN CE4
J 0
(-3265 2560);
DISPLAY 0.617021 (-3265 2560);
PAINT ORANGE (-3265 2560);
FORCEPROP 2 LASTPIN (-3275 2500) $PN CE2
J 0
(-3265 2510);
DISPLAY 0.617021 (-3265 2510);
PAINT ORANGE (-3265 2510);
FORCEPROP 2 LASTPIN (-3275 2450) $PN CK3
J 0
(-3265 2460);
DISPLAY 0.617021 (-3265 2460);
PAINT ORANGE (-3265 2460);
FORCEPROP 2 LASTPIN (-3275 2400) $PN CK1
J 0
(-3265 2410);
DISPLAY 0.617021 (-3265 2410);
PAINT ORANGE (-3265 2410);
FORCEPROP 2 LASTPIN (-3275 2050) $PN CP3
J 0
(-3265 2060);
DISPLAY 0.617021 (-3265 2060);
PAINT ORANGE (-3265 2060);
FORCEPROP 2 LASTPIN (-3275 2000) $PN CR2
J 0
(-3265 2010);
DISPLAY 0.617021 (-3265 2010);
PAINT ORANGE (-3265 2010);
FORCEPROP 2 LASTPIN (-3275 1950) $PN CU2
J 0
(-3265 1960);
DISPLAY 0.617021 (-3265 1960);
PAINT ORANGE (-3265 1960);
FORCEPROP 2 LASTPIN (-3275 1900) $PN CW4
J 0
(-3265 1910);
DISPLAY 0.617021 (-3265 1910);
PAINT ORANGE (-3265 1910);
FORCEPROP 2 LASTPIN (-3275 3300) $PN BM5
J 0
(-3265 3310);
DISPLAY 0.617021 (-3265 3310);
PAINT ORANGE (-3265 3310);
FORCEPROP 2 LASTPIN (-3275 3250) $PN BL4
J 0
(-3265 3260);
DISPLAY 0.617021 (-3265 3260);
PAINT ORANGE (-3265 3260);
FORCEPROP 2 LASTPIN (-3275 3200) $PN BP5
J 0
(-3265 3210);
DISPLAY 0.617021 (-3265 3210);
PAINT ORANGE (-3265 3210);
FORCEPROP 2 LASTPIN (-3275 3150) $PN BU4
J 0
(-3265 3160);
DISPLAY 0.617021 (-3265 3160);
PAINT ORANGE (-3265 3160);
FORCEPROP 2 LASTPIN (-3275 2800) $PN BW4
J 0
(-3265 2810);
DISPLAY 0.617021 (-3265 2810);
PAINT ORANGE (-3265 2810);
FORCEPROP 2 LASTPIN (-3275 2750) $PN CA4
J 0
(-3265 2760);
DISPLAY 0.617021 (-3265 2760);
PAINT ORANGE (-3265 2760);
FORCEPROP 2 LASTPIN (-3275 2700) $PN CB3
J 0
(-3265 2710);
DISPLAY 0.617021 (-3265 2710);
PAINT ORANGE (-3265 2710);
FORCEPROP 2 LASTPIN (-3275 2650) $PN CC2
J 0
(-3265 2660);
DISPLAY 0.617021 (-3265 2660);
PAINT ORANGE (-3265 2660);
FORCEPROP 2 LASTPIN (-3275 2300) $PN CF3
J 0
(-3265 2310);
DISPLAY 0.617021 (-3265 2310);
PAINT ORANGE (-3265 2310);
FORCEPROP 2 LASTPIN (-3275 2250) $PN CG2
J 0
(-3265 2260);
DISPLAY 0.617021 (-3265 2260);
PAINT ORANGE (-3265 2260);
FORCEPROP 2 LASTPIN (-3275 2200) $PN CL2
J 0
(-3265 2210);
DISPLAY 0.617021 (-3265 2210);
PAINT ORANGE (-3265 2210);
FORCEPROP 2 LASTPIN (-3275 2150) $PN CM1
J 0
(-3265 2160);
DISPLAY 0.617021 (-3265 2160);
PAINT ORANGE (-3265 2160);
FORCEPROP 2 LASTPIN (-3275 1800) $PN CT3
J 0
(-3265 1810);
DISPLAY 0.617021 (-3265 1810);
PAINT ORANGE (-3265 1810);
FORCEPROP 2 LASTPIN (-3275 1750) $PN CT1
J 0
(-3265 1760);
DISPLAY 0.617021 (-3265 1760);
PAINT ORANGE (-3265 1760);
FORCEPROP 2 LASTPIN (-3275 1700) $PN CV3
J 0
(-3265 1710);
DISPLAY 0.617021 (-3265 1710);
PAINT ORANGE (-3265 1710);
FORCEPROP 2 LASTPIN (-3275 1650) $PN CY3
J 0
(-3265 1660);
DISPLAY 0.617021 (-3265 1660);
PAINT ORANGE (-3265 1660);
FORCEPROP 2 LASTPIN (-4775 3550) $PN BJ10
J 2
(-4785 3560);
DISPLAY 0.617021 (-4785 3560);
PAINT ORANGE (-4785 3560);
FORCEPROP 2 LASTPIN (-4775 3500) $PN BJ8
J 2
(-4785 3510);
DISPLAY 0.617021 (-4785 3510);
PAINT ORANGE (-4785 3510);
FORCEPROP 2 LASTPIN (-4775 3450) $PN BM7
J 2
(-4785 3460);
DISPLAY 0.617021 (-4785 3460);
PAINT ORANGE (-4785 3460);
FORCEPROP 2 LASTPIN (-4775 3400) $PN BP9
J 2
(-4785 3410);
DISPLAY 0.617021 (-4785 3410);
PAINT ORANGE (-4785 3410);
FORCEPROP 2 LASTPIN (-4775 3050) $PN BP7
J 2
(-4785 3060);
DISPLAY 0.617021 (-4785 3060);
PAINT ORANGE (-4785 3060);
FORCEPROP 2 LASTPIN (-4775 3000) $PN BU6
J 2
(-4785 3010);
DISPLAY 0.617021 (-4785 3010);
PAINT ORANGE (-4785 3010);
FORCEPROP 2 LASTPIN (-4775 2950) $PN BW8
J 2
(-4785 2960);
DISPLAY 0.617021 (-4785 2960);
PAINT ORANGE (-4785 2960);
FORCEPROP 2 LASTPIN (-4775 2900) $PN BV9
J 2
(-4785 2910);
DISPLAY 0.617021 (-4785 2910);
PAINT ORANGE (-4785 2910);
FORCEPROP 2 LASTPIN (-4775 2550) $PN CC8
J 2
(-4785 2560);
DISPLAY 0.617021 (-4785 2560);
PAINT ORANGE (-4785 2560);
FORCEPROP 2 LASTPIN (-4775 2500) $PN CD7
J 2
(-4785 2510);
DISPLAY 0.617021 (-4785 2510);
PAINT ORANGE (-4785 2510);
FORCEPROP 2 LASTPIN (-4775 2450) $PN CF7
J 2
(-4785 2460);
DISPLAY 0.617021 (-4785 2460);
PAINT ORANGE (-4785 2460);
FORCEPROP 2 LASTPIN (-4775 2400) $PN CH7
J 2
(-4785 2410);
DISPLAY 0.617021 (-4785 2410);
PAINT ORANGE (-4785 2410);
FORCEPROP 2 LASTPIN (-4775 2050) $PN CL6
J 2
(-4785 2060);
DISPLAY 0.617021 (-4785 2060);
PAINT ORANGE (-4785 2060);
FORCEPROP 2 LASTPIN (-4775 2000) $PN CN8
J 2
(-4785 2010);
DISPLAY 0.617021 (-4785 2010);
PAINT ORANGE (-4785 2010);
FORCEPROP 2 LASTPIN (-4775 1950) $PN CM9
J 2
(-4785 1960);
DISPLAY 0.617021 (-4785 1960);
PAINT ORANGE (-4785 1960);
FORCEPROP 2 LASTPIN (-4775 1900) $PN CR8
J 2
(-4785 1910);
DISPLAY 0.617021 (-4785 1910);
PAINT ORANGE (-4785 1910);
FORCEPROP 2 LASTPIN (-4775 3300) $PN BK9
J 2
(-4785 3310);
DISPLAY 0.617021 (-4785 3310);
PAINT ORANGE (-4785 3310);
FORCEPROP 2 LASTPIN (-4775 3250) $PN BL8
J 2
(-4785 3260);
DISPLAY 0.617021 (-4785 3260);
PAINT ORANGE (-4785 3260);
FORCEPROP 2 LASTPIN (-4775 3200) $PN BN8
J 2
(-4785 3210);
DISPLAY 0.617021 (-4785 3210);
PAINT ORANGE (-4785 3210);
FORCEPROP 2 LASTPIN (-4775 3150) $PN BR8
J 2
(-4785 3160);
DISPLAY 0.617021 (-4785 3160);
PAINT ORANGE (-4785 3160);
FORCEPROP 2 LASTPIN (-4775 2800) $PN BT7
J 2
(-4785 2810);
DISPLAY 0.617021 (-4785 2810);
PAINT ORANGE (-4785 2810);
FORCEPROP 2 LASTPIN (-4775 2750) $PN BV7
J 2
(-4785 2760);
DISPLAY 0.617021 (-4785 2760);
PAINT ORANGE (-4785 2760);
FORCEPROP 2 LASTPIN (-4775 2700) $PN BY7
J 2
(-4785 2710);
DISPLAY 0.617021 (-4785 2710);
PAINT ORANGE (-4785 2710);
FORCEPROP 2 LASTPIN (-4775 2650) $PN BY9
J 2
(-4785 2660);
DISPLAY 0.617021 (-4785 2660);
PAINT ORANGE (-4785 2660);
FORCEPROP 2 LASTPIN (-4775 2300) $PN CE8
J 2
(-4785 2310);
DISPLAY 0.617021 (-4785 2310);
PAINT ORANGE (-4785 2310);
FORCEPROP 2 LASTPIN (-4775 2250) $PN CE6
J 2
(-4785 2260);
DISPLAY 0.617021 (-4785 2260);
PAINT ORANGE (-4785 2260);
FORCEPROP 2 LASTPIN (-4775 2200) $PN CG8
J 2
(-4785 2210);
DISPLAY 0.617021 (-4785 2210);
PAINT ORANGE (-4785 2210);
FORCEPROP 2 LASTPIN (-4775 2150) $PN CK7
J 2
(-4785 2160);
DISPLAY 0.617021 (-4785 2160);
PAINT ORANGE (-4785 2160);
FORCEPROP 2 LASTPIN (-4775 1800) $PN CM7
J 2
(-4785 1810);
DISPLAY 0.617021 (-4785 1810);
PAINT ORANGE (-4785 1810);
FORCEPROP 2 LASTPIN (-4775 1750) $PN CP7
J 2
(-4785 1760);
DISPLAY 0.617021 (-4785 1760);
PAINT ORANGE (-4785 1760);
FORCEPROP 2 LASTPIN (-4775 1700) $PN CP9
J 2
(-4785 1710);
DISPLAY 0.617021 (-4785 1710);
PAINT ORANGE (-4785 1710);
FORCEPROP 2 LASTPIN (-4775 1650) $PN CT9
J 2
(-4785 1660);
DISPLAY 0.617021 (-4785 1660);
PAINT ORANGE (-4785 1660);
FORCEPROP 1 LAST PACK_TYPE BGA1
J 0
(-4725 3850);
PAINT SKYBLUE (-4725 3850);
DISPLAY INVISIBLE (-4725 3850);
FORCEPROP 2 LAST CDS_LIB chpset_lib
J 0
(-4025 2600);
PAINT ORANGE (-4025 2600);
DISPLAY INVISIBLE (-4025 2600);
FORCEPROP 2 LAST SEC_TYPE BGA1
J 0
(-4725 3850);
DISPLAY 1.021277 (-4725 3850);
PAINT ORANGE (-4725 3850);
DISPLAY INVISIBLE (-4725 3850);
FORCEPROP 2 LAST SEC 11
J 0
(-4725 3850);
DISPLAY 0.680851 (-4725 3850);
PAINT MONO (-4725 3850);
DISPLAY INVISIBLE (-4725 3850);
FORCEPROP 2 LAST CDS_LOCATION U5D1
J 0
(-4725 3800);
DISPLAY 0.617021 (-4725 3800);
PAINT AQUA (-4725 3800);
DISPLAY INVISIBLE (-4725 3800);
FORCEPROP 1 LAST PATH I106
J 0
(-4025 3750);
PAINT GREEN (-4025 3750);
DISPLAY INVISIBLE (-4025 3750);
FORCEPROP 0 LAST ROOM CPU0
J 0
(-4725 3900);
DISPLAY 1.021277 (-4725 3900);
PAINT ORANGE (-4725 3900);
DISPLAY INVISIBLE (-4725 3900);
FORCEADD TAP..1
R 2
(-5450 2000);
FORCEPROP 3 LASTPIN (-5400 2000) SIG_NAME P3E_CPU0_PE2_SS_RXP<2>
J 0
(-5390 2010);
DISPLAY 0.659574 (-5390 2010);
PAINT MONO (-5390 2010);
DISPLAY INVISIBLE (-5390 2010);
FORCEPROP 1 LASTPIN (-5400 2000) BN 2
J 2
(-5388 2008);
DISPLAY 0.617021 (-5388 2008);
PAINT PINK (-5388 2008);
FORCEPROP 2 LAST CDS_LIB mstr_standard
J 0
(-5450 2000);
PAINT MONO (-5450 2000);
DISPLAY INVISIBLE (-5450 2000);
FORCEPROP 1 LAST BODY_TYPE PLUMBING
J 2
(-5450 2050);
DISPLAY 1.446809 (-5450 2050);
PAINT GREEN (-5450 2050);
DISPLAY INVISIBLE (-5450 2050);
FORCEPROP 1 LAST HDL_TAP TRUE
J 2
(-5775 1875);
DISPLAY 1.446809 (-5775 1875);
PAINT GREEN (-5775 1875);
DISPLAY INVISIBLE (-5775 1875);
FORCEPROP 1 LAST PATH I11
J 2
(-5448 2000);
DISPLAY 0.872340 (-5448 2000);
PAINT GREEN (-5448 2000);
DISPLAY INVISIBLE (-5448 2000);
FORCEADD TAP..1
R 2
(-5450 2400);
FORCEPROP 3 LASTPIN (-5400 2400) SIG_NAME P3E_CPU0_PE2_SS_RXP<4>
J 0
(-5390 2410);
DISPLAY 0.659574 (-5390 2410);
PAINT MONO (-5390 2410);
DISPLAY INVISIBLE (-5390 2410);
FORCEPROP 1 LASTPIN (-5400 2400) BN 4
J 2
(-5388 2408);
DISPLAY 0.617021 (-5388 2408);
PAINT PINK (-5388 2408);
FORCEPROP 2 LAST CDS_LIB mstr_standard
J 0
(-5450 2400);
PAINT MONO (-5450 2400);
DISPLAY INVISIBLE (-5450 2400);
FORCEPROP 1 LAST BODY_TYPE PLUMBING
J 2
(-5450 2450);
DISPLAY 1.446809 (-5450 2450);
PAINT GREEN (-5450 2450);
DISPLAY INVISIBLE (-5450 2450);
FORCEPROP 1 LAST HDL_TAP TRUE
J 2
(-5775 2275);
DISPLAY 1.446809 (-5775 2275);
PAINT GREEN (-5775 2275);
DISPLAY INVISIBLE (-5775 2275);
FORCEPROP 1 LAST PATH I12
J 2
(-5448 2400);
DISPLAY 0.872340 (-5448 2400);
PAINT GREEN (-5448 2400);
DISPLAY INVISIBLE (-5448 2400);
FORCEADD TAP..1
R 2
(-5300 2150);
FORCEPROP 3 LASTPIN (-5250 2150) SIG_NAME P3E_CPU0_PE2_SS_RXN<4>
J 0
(-5240 2160);
DISPLAY 0.659574 (-5240 2160);
PAINT MONO (-5240 2160);
DISPLAY INVISIBLE (-5240 2160);
FORCEPROP 1 LASTPIN (-5250 2150) BN 4
J 2
(-5238 2158);
DISPLAY 0.617021 (-5238 2158);
PAINT PINK (-5238 2158);
FORCEPROP 2 LAST CDS_LIB mstr_standard
J 0
(-5300 2150);
PAINT MONO (-5300 2150);
DISPLAY INVISIBLE (-5300 2150);
FORCEPROP 1 LAST BODY_TYPE PLUMBING
J 2
(-5300 2200);
DISPLAY 1.446809 (-5300 2200);
PAINT GREEN (-5300 2200);
DISPLAY INVISIBLE (-5300 2200);
FORCEPROP 1 LAST HDL_TAP TRUE
J 2
(-5625 2025);
DISPLAY 1.446809 (-5625 2025);
PAINT GREEN (-5625 2025);
DISPLAY INVISIBLE (-5625 2025);
FORCEPROP 1 LAST PATH I13
J 2
(-5298 2150);
DISPLAY 0.872340 (-5298 2150);
PAINT GREEN (-5298 2150);
DISPLAY INVISIBLE (-5298 2150);
FORCEADD TAP..1
R 2
(-5300 2250);
FORCEPROP 3 LASTPIN (-5250 2250) SIG_NAME P3E_CPU0_PE2_SS_RXN<6>
J 0
(-5240 2260);
DISPLAY 0.659574 (-5240 2260);
PAINT MONO (-5240 2260);
DISPLAY INVISIBLE (-5240 2260);
FORCEPROP 1 LASTPIN (-5250 2250) BN 6
J 2
(-5238 2258);
DISPLAY 0.617021 (-5238 2258);
PAINT PINK (-5238 2258);
FORCEPROP 2 LAST CDS_LIB mstr_standard
J 0
(-5300 2250);
PAINT MONO (-5300 2250);
DISPLAY INVISIBLE (-5300 2250);
FORCEPROP 1 LAST BODY_TYPE PLUMBING
J 2
(-5300 2300);
DISPLAY 1.446809 (-5300 2300);
PAINT GREEN (-5300 2300);
DISPLAY INVISIBLE (-5300 2300);
FORCEPROP 1 LAST HDL_TAP TRUE
J 2
(-5625 2125);
DISPLAY 1.446809 (-5625 2125);
PAINT GREEN (-5625 2125);
DISPLAY INVISIBLE (-5625 2125);
FORCEPROP 1 LAST PATH I14
J 2
(-5298 2250);
DISPLAY 0.872340 (-5298 2250);
PAINT GREEN (-5298 2250);
DISPLAY INVISIBLE (-5298 2250);
FORCEADD TAP..1
R 2
(-5300 2300);
FORCEPROP 3 LASTPIN (-5250 2300) SIG_NAME P3E_CPU0_PE2_SS_RXN<7>
J 0
(-5240 2310);
DISPLAY 0.659574 (-5240 2310);
PAINT MONO (-5240 2310);
DISPLAY INVISIBLE (-5240 2310);
FORCEPROP 1 LASTPIN (-5250 2300) BN 7
J 2
(-5238 2308);
DISPLAY 0.617021 (-5238 2308);
PAINT PINK (-5238 2308);
FORCEPROP 2 LAST CDS_LIB mstr_standard
J 0
(-5300 2300);
PAINT MONO (-5300 2300);
DISPLAY INVISIBLE (-5300 2300);
FORCEPROP 1 LAST BODY_TYPE PLUMBING
J 2
(-5300 2350);
DISPLAY 1.446809 (-5300 2350);
PAINT GREEN (-5300 2350);
DISPLAY INVISIBLE (-5300 2350);
FORCEPROP 1 LAST HDL_TAP TRUE
J 2
(-5625 2175);
DISPLAY 1.446809 (-5625 2175);
PAINT GREEN (-5625 2175);
DISPLAY INVISIBLE (-5625 2175);
FORCEPROP 1 LAST PATH I15
J 2
(-5298 2300);
DISPLAY 0.872340 (-5298 2300);
PAINT GREEN (-5298 2300);
DISPLAY INVISIBLE (-5298 2300);
FORCEADD TAP..1
R 2
(-5300 2200);
FORCEPROP 3 LASTPIN (-5250 2200) SIG_NAME P3E_CPU0_PE2_SS_RXN<5>
J 0
(-5240 2210);
DISPLAY 0.659574 (-5240 2210);
PAINT MONO (-5240 2210);
DISPLAY INVISIBLE (-5240 2210);
FORCEPROP 1 LASTPIN (-5250 2200) BN 5
J 2
(-5238 2208);
DISPLAY 0.617021 (-5238 2208);
PAINT PINK (-5238 2208);
FORCEPROP 2 LAST CDS_LIB mstr_standard
J 0
(-5300 2200);
PAINT MONO (-5300 2200);
DISPLAY INVISIBLE (-5300 2200);
FORCEPROP 1 LAST BODY_TYPE PLUMBING
J 2
(-5300 2250);
DISPLAY 1.446809 (-5300 2250);
PAINT GREEN (-5300 2250);
DISPLAY INVISIBLE (-5300 2250);
FORCEPROP 1 LAST HDL_TAP TRUE
J 2
(-5625 2075);
DISPLAY 1.446809 (-5625 2075);
PAINT GREEN (-5625 2075);
DISPLAY INVISIBLE (-5625 2075);
FORCEPROP 1 LAST PATH I16
J 2
(-5298 2200);
DISPLAY 0.872340 (-5298 2200);
PAINT GREEN (-5298 2200);
DISPLAY INVISIBLE (-5298 2200);
FORCEADD TAP..1
R 2
(-5450 2550);
FORCEPROP 3 LASTPIN (-5400 2550) SIG_NAME P3E_CPU0_PE2_SS_RXP<7>
J 0
(-5390 2560);
DISPLAY 0.659574 (-5390 2560);
PAINT MONO (-5390 2560);
DISPLAY INVISIBLE (-5390 2560);
FORCEPROP 1 LASTPIN (-5400 2550) BN 7
J 2
(-5388 2558);
DISPLAY 0.617021 (-5388 2558);
PAINT PINK (-5388 2558);
FORCEPROP 2 LAST CDS_LIB mstr_standard
J 0
(-5450 2550);
PAINT MONO (-5450 2550);
DISPLAY INVISIBLE (-5450 2550);
FORCEPROP 1 LAST BODY_TYPE PLUMBING
J 2
(-5450 2600);
DISPLAY 1.446809 (-5450 2600);
PAINT GREEN (-5450 2600);
DISPLAY INVISIBLE (-5450 2600);
FORCEPROP 1 LAST HDL_TAP TRUE
J 2
(-5775 2425);
DISPLAY 1.446809 (-5775 2425);
PAINT GREEN (-5775 2425);
DISPLAY INVISIBLE (-5775 2425);
FORCEPROP 1 LAST PATH I17
J 2
(-5448 2550);
DISPLAY 0.872340 (-5448 2550);
PAINT GREEN (-5448 2550);
DISPLAY INVISIBLE (-5448 2550);
FORCEADD TAP..1
R 2
(-5450 2450);
FORCEPROP 3 LASTPIN (-5400 2450) SIG_NAME P3E_CPU0_PE2_SS_RXP<5>
J 0
(-5390 2460);
DISPLAY 0.659574 (-5390 2460);
PAINT MONO (-5390 2460);
DISPLAY INVISIBLE (-5390 2460);
FORCEPROP 1 LASTPIN (-5400 2450) BN 5
J 2
(-5388 2458);
DISPLAY 0.617021 (-5388 2458);
PAINT PINK (-5388 2458);
FORCEPROP 2 LAST CDS_LIB mstr_standard
J 0
(-5450 2450);
PAINT MONO (-5450 2450);
DISPLAY INVISIBLE (-5450 2450);
FORCEPROP 1 LAST BODY_TYPE PLUMBING
J 2
(-5450 2500);
DISPLAY 1.446809 (-5450 2500);
PAINT GREEN (-5450 2500);
DISPLAY INVISIBLE (-5450 2500);
FORCEPROP 1 LAST HDL_TAP TRUE
J 2
(-5775 2325);
DISPLAY 1.446809 (-5775 2325);
PAINT GREEN (-5775 2325);
DISPLAY INVISIBLE (-5775 2325);
FORCEPROP 1 LAST PATH I18
J 2
(-5448 2450);
DISPLAY 0.872340 (-5448 2450);
PAINT GREEN (-5448 2450);
DISPLAY INVISIBLE (-5448 2450);
FORCEADD TAP..1
R 2
(-5450 2500);
FORCEPROP 3 LASTPIN (-5400 2500) SIG_NAME P3E_CPU0_PE2_SS_RXP<6>
J 0
(-5390 2510);
DISPLAY 0.659574 (-5390 2510);
PAINT MONO (-5390 2510);
DISPLAY INVISIBLE (-5390 2510);
FORCEPROP 1 LASTPIN (-5400 2500) BN 6
J 2
(-5388 2508);
DISPLAY 0.617021 (-5388 2508);
PAINT PINK (-5388 2508);
FORCEPROP 2 LAST CDS_LIB mstr_standard
J 0
(-5450 2500);
PAINT MONO (-5450 2500);
DISPLAY INVISIBLE (-5450 2500);
FORCEPROP 1 LAST BODY_TYPE PLUMBING
J 2
(-5450 2550);
DISPLAY 1.446809 (-5450 2550);
PAINT GREEN (-5450 2550);
DISPLAY INVISIBLE (-5450 2550);
FORCEPROP 1 LAST HDL_TAP TRUE
J 2
(-5775 2375);
DISPLAY 1.446809 (-5775 2375);
PAINT GREEN (-5775 2375);
DISPLAY INVISIBLE (-5775 2375);
FORCEPROP 1 LAST PATH I19
J 2
(-5448 2500);
DISPLAY 0.872340 (-5448 2500);
PAINT GREEN (-5448 2500);
DISPLAY INVISIBLE (-5448 2500);
FORCEADD TAP..1
R 2
(-5300 1650);
FORCEPROP 3 LASTPIN (-5250 1650) SIG_NAME P3E_CPU0_PE2_SS_RXN<0>
J 0
(-5240 1660);
DISPLAY 0.659574 (-5240 1660);
PAINT MONO (-5240 1660);
DISPLAY INVISIBLE (-5240 1660);
FORCEPROP 1 LASTPIN (-5250 1650) BN 0
J 2
(-5238 1658);
DISPLAY 0.617021 (-5238 1658);
PAINT PINK (-5238 1658);
FORCEPROP 2 LAST CDS_LIB mstr_standard
J 0
(-5300 1650);
PAINT MONO (-5300 1650);
DISPLAY INVISIBLE (-5300 1650);
FORCEPROP 1 LAST BODY_TYPE PLUMBING
J 2
(-5300 1700);
DISPLAY 1.446809 (-5300 1700);
PAINT GREEN (-5300 1700);
DISPLAY INVISIBLE (-5300 1700);
FORCEPROP 1 LAST HDL_TAP TRUE
J 2
(-5625 1525);
DISPLAY 1.446809 (-5625 1525);
PAINT GREEN (-5625 1525);
DISPLAY INVISIBLE (-5625 1525);
FORCEPROP 1 LAST PATH I3
J 2
(-5298 1650);
DISPLAY 0.872340 (-5298 1650);
PAINT GREEN (-5298 1650);
DISPLAY INVISIBLE (-5298 1650);
FORCEADD TAP..1
(-2675 1650);
FORCEPROP 3 LASTPIN (-2725 1650) SIG_NAME P3E_CPU0_PE2_SS_TXN<0>
J 0
(-2715 1660);
DISPLAY 0.659574 (-2715 1660);
PAINT MONO (-2715 1660);
DISPLAY INVISIBLE (-2715 1660);
FORCEPROP 1 LASTPIN (-2725 1650) BN 0
J 0
(-2737 1658);
DISPLAY 0.617021 (-2737 1658);
PAINT PINK (-2737 1658);
FORCEPROP 2 LAST CDS_LIB mstr_standard
J 2
(-2675 1650);
PAINT MONO (-2675 1650);
DISPLAY INVISIBLE (-2675 1650);
FORCEPROP 1 LAST BODY_TYPE PLUMBING
J 0
(-2675 1700);
DISPLAY 1.446809 (-2675 1700);
PAINT GREEN (-2675 1700);
DISPLAY INVISIBLE (-2675 1700);
FORCEPROP 1 LAST HDL_TAP TRUE
J 0
(-2350 1525);
DISPLAY 1.446809 (-2350 1525);
PAINT GREEN (-2350 1525);
DISPLAY INVISIBLE (-2350 1525);
FORCEPROP 1 LAST PATH I36
J 0
(-2677 1650);
DISPLAY 0.872340 (-2677 1650);
PAINT GREEN (-2677 1650);
DISPLAY INVISIBLE (-2677 1650);
FORCEADD TAP..1
(-2825 1900);
FORCEPROP 3 LASTPIN (-2875 1900) SIG_NAME P3E_CPU0_PE2_SS_TXP<0>
J 0
(-2865 1910);
DISPLAY 0.659574 (-2865 1910);
PAINT MONO (-2865 1910);
DISPLAY INVISIBLE (-2865 1910);
FORCEPROP 1 LASTPIN (-2875 1900) BN 0
J 0
(-2887 1908);
DISPLAY 0.617021 (-2887 1908);
PAINT PINK (-2887 1908);
FORCEPROP 2 LAST CDS_LIB mstr_standard
J 2
(-2825 1900);
PAINT MONO (-2825 1900);
DISPLAY INVISIBLE (-2825 1900);
FORCEPROP 1 LAST BODY_TYPE PLUMBING
J 0
(-2825 1950);
DISPLAY 1.446809 (-2825 1950);
PAINT GREEN (-2825 1950);
DISPLAY INVISIBLE (-2825 1950);
FORCEPROP 1 LAST HDL_TAP TRUE
J 0
(-2500 1775);
DISPLAY 1.446809 (-2500 1775);
PAINT GREEN (-2500 1775);
DISPLAY INVISIBLE (-2500 1775);
FORCEPROP 1 LAST PATH I37
J 0
(-2827 1900);
DISPLAY 0.872340 (-2827 1900);
PAINT GREEN (-2827 1900);
DISPLAY INVISIBLE (-2827 1900);
FORCEADD TAP..1
(-2675 1700);
FORCEPROP 3 LASTPIN (-2725 1700) SIG_NAME P3E_CPU0_PE2_SS_TXN<1>
J 0
(-2715 1710);
DISPLAY 0.659574 (-2715 1710);
PAINT MONO (-2715 1710);
DISPLAY INVISIBLE (-2715 1710);
FORCEPROP 1 LASTPIN (-2725 1700) BN 1
J 0
(-2737 1708);
DISPLAY 0.617021 (-2737 1708);
PAINT PINK (-2737 1708);
FORCEPROP 2 LAST CDS_LIB mstr_standard
J 2
(-2675 1700);
PAINT MONO (-2675 1700);
DISPLAY INVISIBLE (-2675 1700);
FORCEPROP 1 LAST BODY_TYPE PLUMBING
J 0
(-2675 1750);
DISPLAY 1.446809 (-2675 1750);
PAINT GREEN (-2675 1750);
DISPLAY INVISIBLE (-2675 1750);
FORCEPROP 1 LAST HDL_TAP TRUE
J 0
(-2350 1575);
DISPLAY 1.446809 (-2350 1575);
PAINT GREEN (-2350 1575);
DISPLAY INVISIBLE (-2350 1575);
FORCEPROP 1 LAST PATH I38
J 0
(-2677 1700);
DISPLAY 0.872340 (-2677 1700);
PAINT GREEN (-2677 1700);
DISPLAY INVISIBLE (-2677 1700);
FORCEADD TAP..1
(-2675 1750);
FORCEPROP 3 LASTPIN (-2725 1750) SIG_NAME P3E_CPU0_PE2_SS_TXN<2>
J 0
(-2715 1760);
DISPLAY 0.659574 (-2715 1760);
PAINT MONO (-2715 1760);
DISPLAY INVISIBLE (-2715 1760);
FORCEPROP 1 LASTPIN (-2725 1750) BN 2
J 0
(-2737 1758);
DISPLAY 0.617021 (-2737 1758);
PAINT PINK (-2737 1758);
FORCEPROP 2 LAST CDS_LIB mstr_standard
J 2
(-2675 1750);
PAINT MONO (-2675 1750);
DISPLAY INVISIBLE (-2675 1750);
FORCEPROP 1 LAST BODY_TYPE PLUMBING
J 0
(-2675 1800);
DISPLAY 1.446809 (-2675 1800);
PAINT GREEN (-2675 1800);
DISPLAY INVISIBLE (-2675 1800);
FORCEPROP 1 LAST HDL_TAP TRUE
J 0
(-2350 1625);
DISPLAY 1.446809 (-2350 1625);
PAINT GREEN (-2350 1625);
DISPLAY INVISIBLE (-2350 1625);
FORCEPROP 1 LAST PATH I39
J 0
(-2677 1750);
DISPLAY 0.872340 (-2677 1750);
PAINT GREEN (-2677 1750);
DISPLAY INVISIBLE (-2677 1750);
FORCEADD TAP..1
R 2
(-5300 1700);
FORCEPROP 3 LASTPIN (-5250 1700) SIG_NAME P3E_CPU0_PE2_SS_RXN<1>
J 0
(-5240 1710);
DISPLAY 0.659574 (-5240 1710);
PAINT MONO (-5240 1710);
DISPLAY INVISIBLE (-5240 1710);
FORCEPROP 1 LASTPIN (-5250 1700) BN 1
J 2
(-5238 1708);
DISPLAY 0.617021 (-5238 1708);
PAINT PINK (-5238 1708);
FORCEPROP 2 LAST CDS_LIB mstr_standard
J 0
(-5300 1700);
PAINT MONO (-5300 1700);
DISPLAY INVISIBLE (-5300 1700);
FORCEPROP 1 LAST BODY_TYPE PLUMBING
J 2
(-5300 1750);
DISPLAY 1.446809 (-5300 1750);
PAINT GREEN (-5300 1750);
DISPLAY INVISIBLE (-5300 1750);
FORCEPROP 1 LAST HDL_TAP TRUE
J 2
(-5625 1575);
DISPLAY 1.446809 (-5625 1575);
PAINT GREEN (-5625 1575);
DISPLAY INVISIBLE (-5625 1575);
FORCEPROP 1 LAST PATH I4
J 2
(-5298 1700);
DISPLAY 0.872340 (-5298 1700);
PAINT GREEN (-5298 1700);
DISPLAY INVISIBLE (-5298 1700);
FORCEADD TAP..1
(-2675 1800);
FORCEPROP 3 LASTPIN (-2725 1800) SIG_NAME P3E_CPU0_PE2_SS_TXN<3>
J 0
(-2715 1810);
DISPLAY 0.659574 (-2715 1810);
PAINT MONO (-2715 1810);
DISPLAY INVISIBLE (-2715 1810);
FORCEPROP 1 LASTPIN (-2725 1800) BN 3
J 0
(-2737 1808);
DISPLAY 0.617021 (-2737 1808);
PAINT PINK (-2737 1808);
FORCEPROP 2 LAST CDS_LIB mstr_standard
J 2
(-2675 1800);
PAINT MONO (-2675 1800);
DISPLAY INVISIBLE (-2675 1800);
FORCEPROP 1 LAST BODY_TYPE PLUMBING
J 0
(-2675 1850);
DISPLAY 1.446809 (-2675 1850);
PAINT GREEN (-2675 1850);
DISPLAY INVISIBLE (-2675 1850);
FORCEPROP 1 LAST HDL_TAP TRUE
J 0
(-2350 1675);
DISPLAY 1.446809 (-2350 1675);
PAINT GREEN (-2350 1675);
DISPLAY INVISIBLE (-2350 1675);
FORCEPROP 1 LAST PATH I40
J 0
(-2677 1800);
DISPLAY 0.872340 (-2677 1800);
PAINT GREEN (-2677 1800);
DISPLAY INVISIBLE (-2677 1800);
FORCEADD TAP..1
(-2825 1950);
FORCEPROP 3 LASTPIN (-2875 1950) SIG_NAME P3E_CPU0_PE2_SS_TXP<1>
J 0
(-2865 1960);
DISPLAY 0.659574 (-2865 1960);
PAINT MONO (-2865 1960);
DISPLAY INVISIBLE (-2865 1960);
FORCEPROP 1 LASTPIN (-2875 1950) BN 1
J 0
(-2887 1958);
DISPLAY 0.617021 (-2887 1958);
PAINT PINK (-2887 1958);
FORCEPROP 2 LAST CDS_LIB mstr_standard
J 2
(-2825 1950);
PAINT MONO (-2825 1950);
DISPLAY INVISIBLE (-2825 1950);
FORCEPROP 1 LAST BODY_TYPE PLUMBING
J 0
(-2825 2000);
DISPLAY 1.446809 (-2825 2000);
PAINT GREEN (-2825 2000);
DISPLAY INVISIBLE (-2825 2000);
FORCEPROP 1 LAST HDL_TAP TRUE
J 0
(-2500 1825);
DISPLAY 1.446809 (-2500 1825);
PAINT GREEN (-2500 1825);
DISPLAY INVISIBLE (-2500 1825);
FORCEPROP 1 LAST PATH I41
J 0
(-2827 1950);
DISPLAY 0.872340 (-2827 1950);
PAINT GREEN (-2827 1950);
DISPLAY INVISIBLE (-2827 1950);
FORCEADD TAP..1
(-2825 2000);
FORCEPROP 3 LASTPIN (-2875 2000) SIG_NAME P3E_CPU0_PE2_SS_TXP<2>
J 0
(-2865 2010);
DISPLAY 0.659574 (-2865 2010);
PAINT MONO (-2865 2010);
DISPLAY INVISIBLE (-2865 2010);
FORCEPROP 1 LASTPIN (-2875 2000) BN 2
J 0
(-2887 2008);
DISPLAY 0.617021 (-2887 2008);
PAINT PINK (-2887 2008);
FORCEPROP 2 LAST CDS_LIB mstr_standard
J 2
(-2825 2000);
PAINT MONO (-2825 2000);
DISPLAY INVISIBLE (-2825 2000);
FORCEPROP 1 LAST BODY_TYPE PLUMBING
J 0
(-2825 2050);
DISPLAY 1.446809 (-2825 2050);
PAINT GREEN (-2825 2050);
DISPLAY INVISIBLE (-2825 2050);
FORCEPROP 1 LAST HDL_TAP TRUE
J 0
(-2500 1875);
DISPLAY 1.446809 (-2500 1875);
PAINT GREEN (-2500 1875);
DISPLAY INVISIBLE (-2500 1875);
FORCEPROP 1 LAST PATH I42
J 0
(-2827 2000);
DISPLAY 0.872340 (-2827 2000);
PAINT GREEN (-2827 2000);
DISPLAY INVISIBLE (-2827 2000);
FORCEADD TAP..1
(-2825 2050);
FORCEPROP 3 LASTPIN (-2875 2050) SIG_NAME P3E_CPU0_PE2_SS_TXP<3>
J 0
(-2865 2060);
DISPLAY 0.659574 (-2865 2060);
PAINT MONO (-2865 2060);
DISPLAY INVISIBLE (-2865 2060);
FORCEPROP 1 LASTPIN (-2875 2050) BN 3
J 0
(-2887 2058);
DISPLAY 0.617021 (-2887 2058);
PAINT PINK (-2887 2058);
FORCEPROP 2 LAST CDS_LIB mstr_standard
J 2
(-2825 2050);
PAINT MONO (-2825 2050);
DISPLAY INVISIBLE (-2825 2050);
FORCEPROP 1 LAST BODY_TYPE PLUMBING
J 0
(-2825 2100);
DISPLAY 1.446809 (-2825 2100);
PAINT GREEN (-2825 2100);
DISPLAY INVISIBLE (-2825 2100);
FORCEPROP 1 LAST HDL_TAP TRUE
J 0
(-2500 1925);
DISPLAY 1.446809 (-2500 1925);
PAINT GREEN (-2500 1925);
DISPLAY INVISIBLE (-2500 1925);
FORCEPROP 1 LAST PATH I43
J 0
(-2827 2050);
DISPLAY 0.872340 (-2827 2050);
PAINT GREEN (-2827 2050);
DISPLAY INVISIBLE (-2827 2050);
FORCEADD TAP..1
(-2675 2150);
FORCEPROP 3 LASTPIN (-2725 2150) SIG_NAME P3E_CPU0_PE2_SS_TXN<4>
J 0
(-2715 2160);
DISPLAY 0.659574 (-2715 2160);
PAINT MONO (-2715 2160);
DISPLAY INVISIBLE (-2715 2160);
FORCEPROP 1 LASTPIN (-2725 2150) BN 4
J 0
(-2737 2158);
DISPLAY 0.617021 (-2737 2158);
PAINT PINK (-2737 2158);
FORCEPROP 2 LAST CDS_LIB mstr_standard
J 2
(-2675 2150);
PAINT MONO (-2675 2150);
DISPLAY INVISIBLE (-2675 2150);
FORCEPROP 1 LAST BODY_TYPE PLUMBING
J 0
(-2675 2200);
DISPLAY 1.446809 (-2675 2200);
PAINT GREEN (-2675 2200);
DISPLAY INVISIBLE (-2675 2200);
FORCEPROP 1 LAST HDL_TAP TRUE
J 0
(-2350 2025);
DISPLAY 1.446809 (-2350 2025);
PAINT GREEN (-2350 2025);
DISPLAY INVISIBLE (-2350 2025);
FORCEPROP 1 LAST PATH I44
J 0
(-2677 2150);
DISPLAY 0.872340 (-2677 2150);
PAINT GREEN (-2677 2150);
DISPLAY INVISIBLE (-2677 2150);
FORCEADD TAP..1
(-2825 2400);
FORCEPROP 3 LASTPIN (-2875 2400) SIG_NAME P3E_CPU0_PE2_SS_TXP<4>
J 0
(-2865 2410);
DISPLAY 0.659574 (-2865 2410);
PAINT MONO (-2865 2410);
DISPLAY INVISIBLE (-2865 2410);
FORCEPROP 1 LASTPIN (-2875 2400) BN 4
J 0
(-2887 2408);
DISPLAY 0.617021 (-2887 2408);
PAINT PINK (-2887 2408);
FORCEPROP 2 LAST CDS_LIB mstr_standard
J 2
(-2825 2400);
PAINT MONO (-2825 2400);
DISPLAY INVISIBLE (-2825 2400);
FORCEPROP 1 LAST BODY_TYPE PLUMBING
J 0
(-2825 2450);
DISPLAY 1.446809 (-2825 2450);
PAINT GREEN (-2825 2450);
DISPLAY INVISIBLE (-2825 2450);
FORCEPROP 1 LAST HDL_TAP TRUE
J 0
(-2500 2275);
DISPLAY 1.446809 (-2500 2275);
PAINT GREEN (-2500 2275);
DISPLAY INVISIBLE (-2500 2275);
FORCEPROP 1 LAST PATH I45
J 0
(-2827 2400);
DISPLAY 0.872340 (-2827 2400);
PAINT GREEN (-2827 2400);
DISPLAY INVISIBLE (-2827 2400);
FORCEADD TAP..1
(-2675 2200);
FORCEPROP 3 LASTPIN (-2725 2200) SIG_NAME P3E_CPU0_PE2_SS_TXN<5>
J 0
(-2715 2210);
DISPLAY 0.659574 (-2715 2210);
PAINT MONO (-2715 2210);
DISPLAY INVISIBLE (-2715 2210);
FORCEPROP 1 LASTPIN (-2725 2200) BN 5
J 0
(-2737 2208);
DISPLAY 0.617021 (-2737 2208);
PAINT PINK (-2737 2208);
FORCEPROP 2 LAST CDS_LIB mstr_standard
J 2
(-2675 2200);
PAINT MONO (-2675 2200);
DISPLAY INVISIBLE (-2675 2200);
FORCEPROP 1 LAST BODY_TYPE PLUMBING
J 0
(-2675 2250);
DISPLAY 1.446809 (-2675 2250);
PAINT GREEN (-2675 2250);
DISPLAY INVISIBLE (-2675 2250);
FORCEPROP 1 LAST HDL_TAP TRUE
J 0
(-2350 2075);
DISPLAY 1.446809 (-2350 2075);
PAINT GREEN (-2350 2075);
DISPLAY INVISIBLE (-2350 2075);
FORCEPROP 1 LAST PATH I46
J 0
(-2677 2200);
DISPLAY 0.872340 (-2677 2200);
PAINT GREEN (-2677 2200);
DISPLAY INVISIBLE (-2677 2200);
FORCEADD TAP..1
(-2675 2300);
FORCEPROP 3 LASTPIN (-2725 2300) SIG_NAME P3E_CPU0_PE2_SS_TXN<7>
J 0
(-2715 2310);
DISPLAY 0.659574 (-2715 2310);
PAINT MONO (-2715 2310);
DISPLAY INVISIBLE (-2715 2310);
FORCEPROP 1 LASTPIN (-2725 2300) BN 7
J 0
(-2737 2308);
DISPLAY 0.617021 (-2737 2308);
PAINT PINK (-2737 2308);
FORCEPROP 2 LAST CDS_LIB mstr_standard
J 2
(-2675 2300);
PAINT MONO (-2675 2300);
DISPLAY INVISIBLE (-2675 2300);
FORCEPROP 1 LAST BODY_TYPE PLUMBING
J 0
(-2675 2350);
DISPLAY 1.446809 (-2675 2350);
PAINT GREEN (-2675 2350);
DISPLAY INVISIBLE (-2675 2350);
FORCEPROP 1 LAST HDL_TAP TRUE
J 0
(-2350 2175);
DISPLAY 1.446809 (-2350 2175);
PAINT GREEN (-2350 2175);
DISPLAY INVISIBLE (-2350 2175);
FORCEPROP 1 LAST PATH I47
J 0
(-2677 2300);
DISPLAY 0.872340 (-2677 2300);
PAINT GREEN (-2677 2300);
DISPLAY INVISIBLE (-2677 2300);
FORCEADD TAP..1
(-2675 2250);
FORCEPROP 3 LASTPIN (-2725 2250) SIG_NAME P3E_CPU0_PE2_SS_TXN<6>
J 0
(-2715 2260);
DISPLAY 0.659574 (-2715 2260);
PAINT MONO (-2715 2260);
DISPLAY INVISIBLE (-2715 2260);
FORCEPROP 1 LASTPIN (-2725 2250) BN 6
J 0
(-2737 2258);
DISPLAY 0.617021 (-2737 2258);
PAINT PINK (-2737 2258);
FORCEPROP 2 LAST CDS_LIB mstr_standard
J 2
(-2675 2250);
PAINT MONO (-2675 2250);
DISPLAY INVISIBLE (-2675 2250);
FORCEPROP 1 LAST BODY_TYPE PLUMBING
J 0
(-2675 2300);
DISPLAY 1.446809 (-2675 2300);
PAINT GREEN (-2675 2300);
DISPLAY INVISIBLE (-2675 2300);
FORCEPROP 1 LAST HDL_TAP TRUE
J 0
(-2350 2125);
DISPLAY 1.446809 (-2350 2125);
PAINT GREEN (-2350 2125);
DISPLAY INVISIBLE (-2350 2125);
FORCEPROP 1 LAST PATH I48
J 0
(-2677 2250);
DISPLAY 0.872340 (-2677 2250);
PAINT GREEN (-2677 2250);
DISPLAY INVISIBLE (-2677 2250);
FORCEADD TAP..1
(-2825 2550);
FORCEPROP 3 LASTPIN (-2875 2550) SIG_NAME P3E_CPU0_PE2_SS_TXP<7>
J 0
(-2865 2560);
DISPLAY 0.659574 (-2865 2560);
PAINT MONO (-2865 2560);
DISPLAY INVISIBLE (-2865 2560);
FORCEPROP 1 LASTPIN (-2875 2550) BN 7
J 0
(-2887 2558);
DISPLAY 0.617021 (-2887 2558);
PAINT PINK (-2887 2558);
FORCEPROP 2 LAST CDS_LIB mstr_standard
J 2
(-2825 2550);
PAINT MONO (-2825 2550);
DISPLAY INVISIBLE (-2825 2550);
FORCEPROP 1 LAST BODY_TYPE PLUMBING
J 0
(-2825 2600);
DISPLAY 1.446809 (-2825 2600);
PAINT GREEN (-2825 2600);
DISPLAY INVISIBLE (-2825 2600);
FORCEPROP 1 LAST HDL_TAP TRUE
J 0
(-2500 2425);
DISPLAY 1.446809 (-2500 2425);
PAINT GREEN (-2500 2425);
DISPLAY INVISIBLE (-2500 2425);
FORCEPROP 1 LAST PATH I49
J 0
(-2827 2550);
DISPLAY 0.872340 (-2827 2550);
PAINT GREEN (-2827 2550);
DISPLAY INVISIBLE (-2827 2550);
FORCEADD TAP..1
R 2
(-5300 1750);
FORCEPROP 3 LASTPIN (-5250 1750) SIG_NAME P3E_CPU0_PE2_SS_RXN<2>
J 0
(-5240 1760);
DISPLAY 0.659574 (-5240 1760);
PAINT MONO (-5240 1760);
DISPLAY INVISIBLE (-5240 1760);
FORCEPROP 1 LASTPIN (-5250 1750) BN 2
J 2
(-5238 1758);
DISPLAY 0.617021 (-5238 1758);
PAINT PINK (-5238 1758);
FORCEPROP 2 LAST CDS_LIB mstr_standard
J 0
(-5300 1750);
PAINT MONO (-5300 1750);
DISPLAY INVISIBLE (-5300 1750);
FORCEPROP 1 LAST BODY_TYPE PLUMBING
J 2
(-5300 1800);
DISPLAY 1.446809 (-5300 1800);
PAINT GREEN (-5300 1800);
DISPLAY INVISIBLE (-5300 1800);
FORCEPROP 1 LAST HDL_TAP TRUE
J 2
(-5625 1625);
DISPLAY 1.446809 (-5625 1625);
PAINT GREEN (-5625 1625);
DISPLAY INVISIBLE (-5625 1625);
FORCEPROP 1 LAST PATH I5
J 2
(-5298 1750);
DISPLAY 0.872340 (-5298 1750);
PAINT GREEN (-5298 1750);
DISPLAY INVISIBLE (-5298 1750);
FORCEADD TAP..1
(-2825 2450);
FORCEPROP 3 LASTPIN (-2875 2450) SIG_NAME P3E_CPU0_PE2_SS_TXP<5>
J 0
(-2865 2460);
DISPLAY 0.659574 (-2865 2460);
PAINT MONO (-2865 2460);
DISPLAY INVISIBLE (-2865 2460);
FORCEPROP 1 LASTPIN (-2875 2450) BN 5
J 0
(-2887 2458);
DISPLAY 0.617021 (-2887 2458);
PAINT PINK (-2887 2458);
FORCEPROP 2 LAST CDS_LIB mstr_standard
J 2
(-2825 2450);
PAINT MONO (-2825 2450);
DISPLAY INVISIBLE (-2825 2450);
FORCEPROP 1 LAST BODY_TYPE PLUMBING
J 0
(-2825 2500);
DISPLAY 1.446809 (-2825 2500);
PAINT GREEN (-2825 2500);
DISPLAY INVISIBLE (-2825 2500);
FORCEPROP 1 LAST HDL_TAP TRUE
J 0
(-2500 2325);
DISPLAY 1.446809 (-2500 2325);
PAINT GREEN (-2500 2325);
DISPLAY INVISIBLE (-2500 2325);
FORCEPROP 1 LAST PATH I50
J 0
(-2827 2450);
DISPLAY 0.872340 (-2827 2450);
PAINT GREEN (-2827 2450);
DISPLAY INVISIBLE (-2827 2450);
FORCEADD TAP..1
(-2825 2500);
FORCEPROP 3 LASTPIN (-2875 2500) SIG_NAME P3E_CPU0_PE2_SS_TXP<6>
J 0
(-2865 2510);
DISPLAY 0.659574 (-2865 2510);
PAINT MONO (-2865 2510);
DISPLAY INVISIBLE (-2865 2510);
FORCEPROP 1 LASTPIN (-2875 2500) BN 6
J 0
(-2887 2508);
DISPLAY 0.617021 (-2887 2508);
PAINT PINK (-2887 2508);
FORCEPROP 2 LAST CDS_LIB mstr_standard
J 2
(-2825 2500);
PAINT MONO (-2825 2500);
DISPLAY INVISIBLE (-2825 2500);
FORCEPROP 1 LAST BODY_TYPE PLUMBING
J 0
(-2825 2550);
DISPLAY 1.446809 (-2825 2550);
PAINT GREEN (-2825 2550);
DISPLAY INVISIBLE (-2825 2550);
FORCEPROP 1 LAST HDL_TAP TRUE
J 0
(-2500 2375);
DISPLAY 1.446809 (-2500 2375);
PAINT GREEN (-2500 2375);
DISPLAY INVISIBLE (-2500 2375);
FORCEPROP 1 LAST PATH I51
J 0
(-2827 2500);
DISPLAY 0.872340 (-2827 2500);
PAINT GREEN (-2827 2500);
DISPLAY INVISIBLE (-2827 2500);
FORCEADD TAP..1
R 2
(-5300 1800);
FORCEPROP 3 LASTPIN (-5250 1800) SIG_NAME P3E_CPU0_PE2_SS_RXN<3>
J 0
(-5240 1810);
DISPLAY 0.659574 (-5240 1810);
PAINT MONO (-5240 1810);
DISPLAY INVISIBLE (-5240 1810);
FORCEPROP 1 LASTPIN (-5250 1800) BN 3
J 2
(-5238 1808);
DISPLAY 0.617021 (-5238 1808);
PAINT PINK (-5238 1808);
FORCEPROP 2 LAST CDS_LIB mstr_standard
J 0
(-5300 1800);
PAINT MONO (-5300 1800);
DISPLAY INVISIBLE (-5300 1800);
FORCEPROP 1 LAST BODY_TYPE PLUMBING
J 2
(-5300 1850);
DISPLAY 1.446809 (-5300 1850);
PAINT GREEN (-5300 1850);
DISPLAY INVISIBLE (-5300 1850);
FORCEPROP 1 LAST HDL_TAP TRUE
J 2
(-5625 1675);
DISPLAY 1.446809 (-5625 1675);
PAINT GREEN (-5625 1675);
DISPLAY INVISIBLE (-5625 1675);
FORCEPROP 1 LAST PATH I6
J 2
(-5298 1800);
DISPLAY 0.872340 (-5298 1800);
PAINT GREEN (-5298 1800);
DISPLAY INVISIBLE (-5298 1800);
FORCEADD TAP..1
R 2
(-5450 1900);
FORCEPROP 3 LASTPIN (-5400 1900) SIG_NAME P3E_CPU0_PE2_SS_RXP<0>
J 0
(-5390 1910);
DISPLAY 0.659574 (-5390 1910);
PAINT MONO (-5390 1910);
DISPLAY INVISIBLE (-5390 1910);
FORCEPROP 1 LASTPIN (-5400 1900) BN 0
J 2
(-5388 1908);
DISPLAY 0.617021 (-5388 1908);
PAINT PINK (-5388 1908);
FORCEPROP 2 LAST CDS_LIB mstr_standard
J 0
(-5450 1900);
PAINT MONO (-5450 1900);
DISPLAY INVISIBLE (-5450 1900);
FORCEPROP 1 LAST BODY_TYPE PLUMBING
J 2
(-5450 1950);
DISPLAY 1.446809 (-5450 1950);
PAINT GREEN (-5450 1950);
DISPLAY INVISIBLE (-5450 1950);
FORCEPROP 1 LAST HDL_TAP TRUE
J 2
(-5775 1775);
DISPLAY 1.446809 (-5775 1775);
PAINT GREEN (-5775 1775);
DISPLAY INVISIBLE (-5775 1775);
FORCEPROP 1 LAST PATH I7
J 2
(-5448 1900);
DISPLAY 0.872340 (-5448 1900);
PAINT GREEN (-5448 1900);
DISPLAY INVISIBLE (-5448 1900);
FORCEADD OFFPAGE..2
(-1725 3625);
FORCEPROP 2 LAST $XR0 105 
J 0
(-1536 3625);
DISPLAY 0.638298 (-1536 3625);
PAINT MONO (-1536 3625);
FORCEPROP 2 LAST CDS_LIB mstr_standard
J 0
(-1725 3625);
PAINT MONO (-1725 3625);
DISPLAY INVISIBLE (-1725 3625);
FORCEPROP 1 LAST OFFPAGE TRUE
J 0
(-1400 3500);
DISPLAY 1.170213 (-1400 3500);
PAINT GREEN (-1400 3500);
DISPLAY INVISIBLE (-1400 3500);
FORCEPROP 1 LAST COMMENT_BODY TRUE
J 0
(-1770 3530);
DISPLAY 1.170213 (-1770 3530);
PAINT GREEN (-1770 3530);
DISPLAY INVISIBLE (-1770 3530);
FORCEPROP 2 LAST PATH I70
J 0
(-1400 3675);
DISPLAY 1.021277 (-1400 3675);
PAINT ORANGE (-1400 3675);
DISPLAY INVISIBLE (-1400 3675);
FORCEADD OFFPAGE..2
(-1725 3575);
FORCEPROP 2 LAST $XR0 105 
J 0
(-1536 3575);
DISPLAY 0.638298 (-1536 3575);
PAINT MONO (-1536 3575);
FORCEPROP 2 LAST CDS_LIB mstr_standard
J 0
(-1725 3575);
PAINT MONO (-1725 3575);
DISPLAY INVISIBLE (-1725 3575);
FORCEPROP 1 LAST OFFPAGE TRUE
J 0
(-1400 3450);
DISPLAY 1.170213 (-1400 3450);
PAINT GREEN (-1400 3450);
DISPLAY INVISIBLE (-1400 3450);
FORCEPROP 1 LAST COMMENT_BODY TRUE
J 0
(-1770 3480);
DISPLAY 1.170213 (-1770 3480);
PAINT GREEN (-1770 3480);
DISPLAY INVISIBLE (-1770 3480);
FORCEPROP 2 LAST PATH I71
J 0
(-1400 3625);
DISPLAY 1.021277 (-1400 3625);
PAINT ORANGE (-1400 3625);
DISPLAY INVISIBLE (-1400 3625);
FORCEADD TAP..1
(-2675 3200);
FORCEPROP 3 LASTPIN (-2725 3200) SIG_NAME P3E_CPU0_PE2_SS_TXN<13>
J 0
(-2715 3210);
DISPLAY 0.659574 (-2715 3210);
PAINT MONO (-2715 3210);
DISPLAY INVISIBLE (-2715 3210);
FORCEPROP 1 LASTPIN (-2725 3200) BN 13
J 0
(-2737 3208);
DISPLAY 0.617021 (-2737 3208);
PAINT PINK (-2737 3208);
FORCEPROP 2 LAST CDS_LIB mstr_standard
J 2
(-2675 3200);
PAINT MONO (-2675 3200);
DISPLAY INVISIBLE (-2675 3200);
FORCEPROP 1 LAST BODY_TYPE PLUMBING
J 0
(-2675 3250);
DISPLAY 1.446809 (-2675 3250);
PAINT GREEN (-2675 3250);
DISPLAY INVISIBLE (-2675 3250);
FORCEPROP 1 LAST HDL_TAP TRUE
J 0
(-2350 3075);
DISPLAY 1.446809 (-2350 3075);
PAINT GREEN (-2350 3075);
DISPLAY INVISIBLE (-2350 3075);
FORCEPROP 1 LAST PATH I72
J 0
(-2677 3200);
DISPLAY 0.872340 (-2677 3200);
PAINT GREEN (-2677 3200);
DISPLAY INVISIBLE (-2677 3200);
FORCEADD TAP..1
(-2675 3300);
FORCEPROP 3 LASTPIN (-2725 3300) SIG_NAME P3E_CPU0_PE2_SS_TXN<15>
J 0
(-2715 3310);
DISPLAY 0.659574 (-2715 3310);
PAINT MONO (-2715 3310);
DISPLAY INVISIBLE (-2715 3310);
FORCEPROP 1 LASTPIN (-2725 3300) BN 15
J 0
(-2737 3308);
DISPLAY 0.617021 (-2737 3308);
PAINT PINK (-2737 3308);
FORCEPROP 2 LAST CDS_LIB mstr_standard
J 2
(-2675 3300);
PAINT MONO (-2675 3300);
DISPLAY INVISIBLE (-2675 3300);
FORCEPROP 1 LAST BODY_TYPE PLUMBING
J 0
(-2675 3350);
DISPLAY 1.446809 (-2675 3350);
PAINT GREEN (-2675 3350);
DISPLAY INVISIBLE (-2675 3350);
FORCEPROP 1 LAST HDL_TAP TRUE
J 0
(-2350 3175);
DISPLAY 1.446809 (-2350 3175);
PAINT GREEN (-2350 3175);
DISPLAY INVISIBLE (-2350 3175);
FORCEPROP 1 LAST PATH I73
J 0
(-2677 3300);
DISPLAY 0.872340 (-2677 3300);
PAINT GREEN (-2677 3300);
DISPLAY INVISIBLE (-2677 3300);
FORCEADD TAP..1
(-2675 3250);
FORCEPROP 3 LASTPIN (-2725 3250) SIG_NAME P3E_CPU0_PE2_SS_TXN<14>
J 0
(-2715 3260);
DISPLAY 0.659574 (-2715 3260);
PAINT MONO (-2715 3260);
DISPLAY INVISIBLE (-2715 3260);
FORCEPROP 1 LASTPIN (-2725 3250) BN 14
J 0
(-2737 3258);
DISPLAY 0.617021 (-2737 3258);
PAINT PINK (-2737 3258);
FORCEPROP 2 LAST CDS_LIB mstr_standard
J 2
(-2675 3250);
PAINT MONO (-2675 3250);
DISPLAY INVISIBLE (-2675 3250);
FORCEPROP 1 LAST BODY_TYPE PLUMBING
J 0
(-2675 3300);
DISPLAY 1.446809 (-2675 3300);
PAINT GREEN (-2675 3300);
DISPLAY INVISIBLE (-2675 3300);
FORCEPROP 1 LAST HDL_TAP TRUE
J 0
(-2350 3125);
DISPLAY 1.446809 (-2350 3125);
PAINT GREEN (-2350 3125);
DISPLAY INVISIBLE (-2350 3125);
FORCEPROP 1 LAST PATH I74
J 0
(-2677 3250);
DISPLAY 0.872340 (-2677 3250);
PAINT GREEN (-2677 3250);
DISPLAY INVISIBLE (-2677 3250);
FORCEADD TAP..1
(-2675 3150);
FORCEPROP 3 LASTPIN (-2725 3150) SIG_NAME P3E_CPU0_PE2_SS_TXN<12>
J 0
(-2715 3160);
DISPLAY 0.659574 (-2715 3160);
PAINT MONO (-2715 3160);
DISPLAY INVISIBLE (-2715 3160);
FORCEPROP 1 LASTPIN (-2725 3150) BN 12
J 0
(-2737 3158);
DISPLAY 0.617021 (-2737 3158);
PAINT PINK (-2737 3158);
FORCEPROP 2 LAST CDS_LIB mstr_standard
J 2
(-2675 3150);
PAINT MONO (-2675 3150);
DISPLAY INVISIBLE (-2675 3150);
FORCEPROP 1 LAST BODY_TYPE PLUMBING
J 0
(-2675 3200);
DISPLAY 1.446809 (-2675 3200);
PAINT GREEN (-2675 3200);
DISPLAY INVISIBLE (-2675 3200);
FORCEPROP 1 LAST HDL_TAP TRUE
J 0
(-2350 3025);
DISPLAY 1.446809 (-2350 3025);
PAINT GREEN (-2350 3025);
DISPLAY INVISIBLE (-2350 3025);
FORCEPROP 1 LAST PATH I75
J 0
(-2677 3150);
DISPLAY 0.872340 (-2677 3150);
PAINT GREEN (-2677 3150);
DISPLAY INVISIBLE (-2677 3150);
FORCEADD TAP..1
(-2825 3500);
FORCEPROP 3 LASTPIN (-2875 3500) SIG_NAME P3E_CPU0_PE2_SS_TXP<14>
J 0
(-2865 3510);
DISPLAY 0.659574 (-2865 3510);
PAINT MONO (-2865 3510);
DISPLAY INVISIBLE (-2865 3510);
FORCEPROP 1 LASTPIN (-2875 3500) BN 14
J 0
(-2887 3508);
DISPLAY 0.617021 (-2887 3508);
PAINT PINK (-2887 3508);
FORCEPROP 2 LAST CDS_LIB mstr_standard
J 2
(-2825 3500);
PAINT MONO (-2825 3500);
DISPLAY INVISIBLE (-2825 3500);
FORCEPROP 1 LAST BODY_TYPE PLUMBING
J 0
(-2825 3550);
DISPLAY 1.446809 (-2825 3550);
PAINT GREEN (-2825 3550);
DISPLAY INVISIBLE (-2825 3550);
FORCEPROP 1 LAST HDL_TAP TRUE
J 0
(-2500 3375);
DISPLAY 1.446809 (-2500 3375);
PAINT GREEN (-2500 3375);
DISPLAY INVISIBLE (-2500 3375);
FORCEPROP 1 LAST PATH I76
J 0
(-2827 3500);
DISPLAY 0.872340 (-2827 3500);
PAINT GREEN (-2827 3500);
DISPLAY INVISIBLE (-2827 3500);
FORCEADD TAP..1
(-2825 3550);
FORCEPROP 3 LASTPIN (-2875 3550) SIG_NAME P3E_CPU0_PE2_SS_TXP<15>
J 0
(-2865 3560);
DISPLAY 0.659574 (-2865 3560);
PAINT MONO (-2865 3560);
DISPLAY INVISIBLE (-2865 3560);
FORCEPROP 1 LASTPIN (-2875 3550) BN 15
J 0
(-2887 3558);
DISPLAY 0.617021 (-2887 3558);
PAINT PINK (-2887 3558);
FORCEPROP 2 LAST CDS_LIB mstr_standard
J 2
(-2825 3550);
PAINT MONO (-2825 3550);
DISPLAY INVISIBLE (-2825 3550);
FORCEPROP 1 LAST BODY_TYPE PLUMBING
J 0
(-2825 3600);
DISPLAY 1.446809 (-2825 3600);
PAINT GREEN (-2825 3600);
DISPLAY INVISIBLE (-2825 3600);
FORCEPROP 1 LAST HDL_TAP TRUE
J 0
(-2500 3425);
DISPLAY 1.446809 (-2500 3425);
PAINT GREEN (-2500 3425);
DISPLAY INVISIBLE (-2500 3425);
FORCEPROP 1 LAST PATH I77
J 0
(-2827 3550);
DISPLAY 0.872340 (-2827 3550);
PAINT GREEN (-2827 3550);
DISPLAY INVISIBLE (-2827 3550);
FORCEADD TAP..1
(-2825 3450);
FORCEPROP 3 LASTPIN (-2875 3450) SIG_NAME P3E_CPU0_PE2_SS_TXP<13>
J 0
(-2865 3460);
DISPLAY 0.659574 (-2865 3460);
PAINT MONO (-2865 3460);
DISPLAY INVISIBLE (-2865 3460);
FORCEPROP 1 LASTPIN (-2875 3450) BN 13
J 0
(-2887 3458);
DISPLAY 0.617021 (-2887 3458);
PAINT PINK (-2887 3458);
FORCEPROP 2 LAST CDS_LIB mstr_standard
J 2
(-2825 3450);
PAINT MONO (-2825 3450);
DISPLAY INVISIBLE (-2825 3450);
FORCEPROP 1 LAST BODY_TYPE PLUMBING
J 0
(-2825 3500);
DISPLAY 1.446809 (-2825 3500);
PAINT GREEN (-2825 3500);
DISPLAY INVISIBLE (-2825 3500);
FORCEPROP 1 LAST HDL_TAP TRUE
J 0
(-2500 3325);
DISPLAY 1.446809 (-2500 3325);
PAINT GREEN (-2500 3325);
DISPLAY INVISIBLE (-2500 3325);
FORCEPROP 1 LAST PATH I78
J 0
(-2827 3450);
DISPLAY 0.872340 (-2827 3450);
PAINT GREEN (-2827 3450);
DISPLAY INVISIBLE (-2827 3450);
FORCEADD TAP..1
(-2825 3400);
FORCEPROP 3 LASTPIN (-2875 3400) SIG_NAME P3E_CPU0_PE2_SS_TXP<12>
J 0
(-2865 3410);
DISPLAY 0.659574 (-2865 3410);
PAINT MONO (-2865 3410);
DISPLAY INVISIBLE (-2865 3410);
FORCEPROP 1 LASTPIN (-2875 3400) BN 12
J 0
(-2887 3408);
DISPLAY 0.617021 (-2887 3408);
PAINT PINK (-2887 3408);
FORCEPROP 2 LAST CDS_LIB mstr_standard
J 2
(-2825 3400);
PAINT MONO (-2825 3400);
DISPLAY INVISIBLE (-2825 3400);
FORCEPROP 1 LAST BODY_TYPE PLUMBING
J 0
(-2825 3450);
DISPLAY 1.446809 (-2825 3450);
PAINT GREEN (-2825 3450);
DISPLAY INVISIBLE (-2825 3450);
FORCEPROP 1 LAST HDL_TAP TRUE
J 0
(-2500 3275);
DISPLAY 1.446809 (-2500 3275);
PAINT GREEN (-2500 3275);
DISPLAY INVISIBLE (-2500 3275);
FORCEPROP 1 LAST PATH I79
J 0
(-2827 3400);
DISPLAY 0.872340 (-2827 3400);
PAINT GREEN (-2827 3400);
DISPLAY INVISIBLE (-2827 3400);
FORCEADD TAP..1
(-2825 3050);
FORCEPROP 3 LASTPIN (-2875 3050) SIG_NAME P3E_CPU0_PE2_SS_TXP<11>
J 0
(-2865 3060);
DISPLAY 0.659574 (-2865 3060);
PAINT MONO (-2865 3060);
DISPLAY INVISIBLE (-2865 3060);
FORCEPROP 1 LASTPIN (-2875 3050) BN 11
J 0
(-2862 3058);
DISPLAY 0.617021 (-2862 3058);
PAINT PINK (-2862 3058);
FORCEPROP 2 LAST CDS_LIB mstr_standard
J 2
(-2825 3050);
PAINT MONO (-2825 3050);
DISPLAY INVISIBLE (-2825 3050);
FORCEPROP 1 LAST BODY_TYPE PLUMBING
J 0
(-2825 3100);
DISPLAY 1.446809 (-2825 3100);
PAINT GREEN (-2825 3100);
DISPLAY INVISIBLE (-2825 3100);
FORCEPROP 1 LAST HDL_TAP TRUE
J 0
(-2500 2925);
DISPLAY 1.446809 (-2500 2925);
PAINT GREEN (-2500 2925);
DISPLAY INVISIBLE (-2500 2925);
FORCEPROP 1 LAST PATH I80
J 0
(-2827 3050);
DISPLAY 0.872340 (-2827 3050);
PAINT GREEN (-2827 3050);
DISPLAY INVISIBLE (-2827 3050);
FORCEADD TAP..1
(-2675 2800);
FORCEPROP 3 LASTPIN (-2725 2800) SIG_NAME P3E_CPU0_PE2_SS_TXN<11>
J 0
(-2715 2810);
DISPLAY 0.659574 (-2715 2810);
PAINT MONO (-2715 2810);
DISPLAY INVISIBLE (-2715 2810);
FORCEPROP 1 LASTPIN (-2725 2800) BN 11
J 0
(-2737 2808);
DISPLAY 0.617021 (-2737 2808);
PAINT PINK (-2737 2808);
FORCEPROP 2 LAST CDS_LIB mstr_standard
J 2
(-2675 2800);
PAINT MONO (-2675 2800);
DISPLAY INVISIBLE (-2675 2800);
FORCEPROP 1 LAST BODY_TYPE PLUMBING
J 0
(-2675 2850);
DISPLAY 1.446809 (-2675 2850);
PAINT GREEN (-2675 2850);
DISPLAY INVISIBLE (-2675 2850);
FORCEPROP 1 LAST HDL_TAP TRUE
J 0
(-2350 2675);
DISPLAY 1.446809 (-2350 2675);
PAINT GREEN (-2350 2675);
DISPLAY INVISIBLE (-2350 2675);
FORCEPROP 1 LAST PATH I81
J 0
(-2677 2800);
DISPLAY 0.872340 (-2677 2800);
PAINT GREEN (-2677 2800);
DISPLAY INVISIBLE (-2677 2800);
FORCEADD TAP..1
(-2675 2750);
FORCEPROP 3 LASTPIN (-2725 2750) SIG_NAME P3E_CPU0_PE2_SS_TXN<10>
J 0
(-2715 2760);
DISPLAY 0.659574 (-2715 2760);
PAINT MONO (-2715 2760);
DISPLAY INVISIBLE (-2715 2760);
FORCEPROP 1 LASTPIN (-2725 2750) BN 10
J 0
(-2737 2758);
DISPLAY 0.617021 (-2737 2758);
PAINT PINK (-2737 2758);
FORCEPROP 2 LAST CDS_LIB mstr_standard
J 2
(-2675 2750);
PAINT MONO (-2675 2750);
DISPLAY INVISIBLE (-2675 2750);
FORCEPROP 1 LAST BODY_TYPE PLUMBING
J 0
(-2675 2800);
DISPLAY 1.446809 (-2675 2800);
PAINT GREEN (-2675 2800);
DISPLAY INVISIBLE (-2675 2800);
FORCEPROP 1 LAST HDL_TAP TRUE
J 0
(-2350 2625);
DISPLAY 1.446809 (-2350 2625);
PAINT GREEN (-2350 2625);
DISPLAY INVISIBLE (-2350 2625);
FORCEPROP 1 LAST PATH I82
J 0
(-2677 2750);
DISPLAY 0.872340 (-2677 2750);
PAINT GREEN (-2677 2750);
DISPLAY INVISIBLE (-2677 2750);
FORCEADD TAP..1
(-2675 2700);
FORCEPROP 3 LASTPIN (-2725 2700) SIG_NAME P3E_CPU0_PE2_SS_TXN<9>
J 0
(-2715 2710);
DISPLAY 0.659574 (-2715 2710);
PAINT MONO (-2715 2710);
DISPLAY INVISIBLE (-2715 2710);
FORCEPROP 1 LASTPIN (-2725 2700) BN 9
J 0
(-2737 2708);
DISPLAY 0.617021 (-2737 2708);
PAINT PINK (-2737 2708);
FORCEPROP 2 LAST CDS_LIB mstr_standard
J 2
(-2675 2700);
PAINT MONO (-2675 2700);
DISPLAY INVISIBLE (-2675 2700);
FORCEPROP 1 LAST BODY_TYPE PLUMBING
J 0
(-2675 2750);
DISPLAY 1.446809 (-2675 2750);
PAINT GREEN (-2675 2750);
DISPLAY INVISIBLE (-2675 2750);
FORCEPROP 1 LAST HDL_TAP TRUE
J 0
(-2350 2575);
DISPLAY 1.446809 (-2350 2575);
PAINT GREEN (-2350 2575);
DISPLAY INVISIBLE (-2350 2575);
FORCEPROP 1 LAST PATH I83
J 0
(-2677 2700);
DISPLAY 0.872340 (-2677 2700);
PAINT GREEN (-2677 2700);
DISPLAY INVISIBLE (-2677 2700);
FORCEADD TAP..1
(-2675 2650);
FORCEPROP 3 LASTPIN (-2725 2650) SIG_NAME P3E_CPU0_PE2_SS_TXN<8>
J 0
(-2715 2660);
DISPLAY 0.659574 (-2715 2660);
PAINT MONO (-2715 2660);
DISPLAY INVISIBLE (-2715 2660);
FORCEPROP 1 LASTPIN (-2725 2650) BN 8
J 0
(-2737 2658);
DISPLAY 0.617021 (-2737 2658);
PAINT PINK (-2737 2658);
FORCEPROP 2 LAST CDS_LIB mstr_standard
J 2
(-2675 2650);
PAINT MONO (-2675 2650);
DISPLAY INVISIBLE (-2675 2650);
FORCEPROP 1 LAST BODY_TYPE PLUMBING
J 0
(-2675 2700);
DISPLAY 1.446809 (-2675 2700);
PAINT GREEN (-2675 2700);
DISPLAY INVISIBLE (-2675 2700);
FORCEPROP 1 LAST HDL_TAP TRUE
J 0
(-2350 2525);
DISPLAY 1.446809 (-2350 2525);
PAINT GREEN (-2350 2525);
DISPLAY INVISIBLE (-2350 2525);
FORCEPROP 1 LAST PATH I84
J 0
(-2677 2650);
DISPLAY 0.872340 (-2677 2650);
PAINT GREEN (-2677 2650);
DISPLAY INVISIBLE (-2677 2650);
FORCEADD TAP..1
(-2825 3000);
FORCEPROP 3 LASTPIN (-2875 3000) SIG_NAME P3E_CPU0_PE2_SS_TXP<10>
J 0
(-2865 3010);
DISPLAY 0.659574 (-2865 3010);
PAINT MONO (-2865 3010);
DISPLAY INVISIBLE (-2865 3010);
FORCEPROP 1 LASTPIN (-2875 3000) BN 10
J 0
(-2887 3008);
DISPLAY 0.617021 (-2887 3008);
PAINT PINK (-2887 3008);
FORCEPROP 2 LAST CDS_LIB mstr_standard
J 2
(-2825 3000);
PAINT MONO (-2825 3000);
DISPLAY INVISIBLE (-2825 3000);
FORCEPROP 1 LAST BODY_TYPE PLUMBING
J 0
(-2825 3050);
DISPLAY 1.446809 (-2825 3050);
PAINT GREEN (-2825 3050);
DISPLAY INVISIBLE (-2825 3050);
FORCEPROP 1 LAST HDL_TAP TRUE
J 0
(-2500 2875);
DISPLAY 1.446809 (-2500 2875);
PAINT GREEN (-2500 2875);
DISPLAY INVISIBLE (-2500 2875);
FORCEPROP 1 LAST PATH I85
J 0
(-2827 3000);
DISPLAY 0.872340 (-2827 3000);
PAINT GREEN (-2827 3000);
DISPLAY INVISIBLE (-2827 3000);
FORCEADD TAP..1
(-2825 2950);
FORCEPROP 3 LASTPIN (-2875 2950) SIG_NAME P3E_CPU0_PE2_SS_TXP<9>
J 0
(-2865 2960);
DISPLAY 0.659574 (-2865 2960);
PAINT MONO (-2865 2960);
DISPLAY INVISIBLE (-2865 2960);
FORCEPROP 1 LASTPIN (-2875 2950) BN 9
J 0
(-2887 2958);
DISPLAY 0.617021 (-2887 2958);
PAINT PINK (-2887 2958);
FORCEPROP 2 LAST CDS_LIB mstr_standard
J 2
(-2825 2950);
PAINT MONO (-2825 2950);
DISPLAY INVISIBLE (-2825 2950);
FORCEPROP 1 LAST BODY_TYPE PLUMBING
J 0
(-2825 3000);
DISPLAY 1.446809 (-2825 3000);
PAINT GREEN (-2825 3000);
DISPLAY INVISIBLE (-2825 3000);
FORCEPROP 1 LAST HDL_TAP TRUE
J 0
(-2500 2825);
DISPLAY 1.446809 (-2500 2825);
PAINT GREEN (-2500 2825);
DISPLAY INVISIBLE (-2500 2825);
FORCEPROP 1 LAST PATH I86
J 0
(-2827 2950);
DISPLAY 0.872340 (-2827 2950);
PAINT GREEN (-2827 2950);
DISPLAY INVISIBLE (-2827 2950);
FORCEADD TAP..1
(-2825 2900);
FORCEPROP 3 LASTPIN (-2875 2900) SIG_NAME P3E_CPU0_PE2_SS_TXP<8>
J 0
(-2865 2910);
DISPLAY 0.659574 (-2865 2910);
PAINT MONO (-2865 2910);
DISPLAY INVISIBLE (-2865 2910);
FORCEPROP 1 LASTPIN (-2875 2900) BN 8
J 0
(-2887 2908);
DISPLAY 0.617021 (-2887 2908);
PAINT PINK (-2887 2908);
FORCEPROP 2 LAST CDS_LIB mstr_standard
J 2
(-2825 2900);
PAINT MONO (-2825 2900);
DISPLAY INVISIBLE (-2825 2900);
FORCEPROP 1 LAST BODY_TYPE PLUMBING
J 0
(-2825 2950);
DISPLAY 1.446809 (-2825 2950);
PAINT GREEN (-2825 2950);
DISPLAY INVISIBLE (-2825 2950);
FORCEPROP 1 LAST HDL_TAP TRUE
J 0
(-2500 2775);
DISPLAY 1.446809 (-2500 2775);
PAINT GREEN (-2500 2775);
DISPLAY INVISIBLE (-2500 2775);
FORCEPROP 1 LAST PATH I87
J 0
(-2827 2900);
DISPLAY 0.872340 (-2827 2900);
PAINT GREEN (-2827 2900);
DISPLAY INVISIBLE (-2827 2900);
FORCEADD TAP..1
R 2
(-5300 3300);
FORCEPROP 3 LASTPIN (-5250 3300) SIG_NAME P3E_CPU0_PE2_SS_RXN<15>
J 0
(-5240 3310);
DISPLAY 0.659574 (-5240 3310);
PAINT MONO (-5240 3310);
DISPLAY INVISIBLE (-5240 3310);
FORCEPROP 1 LASTPIN (-5250 3300) BN 15
J 2
(-5238 3308);
DISPLAY 0.617021 (-5238 3308);
PAINT PINK (-5238 3308);
FORCEPROP 2 LAST CDS_LIB mstr_standard
J 0
(-5300 3300);
PAINT MONO (-5300 3300);
DISPLAY INVISIBLE (-5300 3300);
FORCEPROP 1 LAST BODY_TYPE PLUMBING
J 2
(-5300 3350);
DISPLAY 1.446809 (-5300 3350);
PAINT GREEN (-5300 3350);
DISPLAY INVISIBLE (-5300 3350);
FORCEPROP 1 LAST HDL_TAP TRUE
J 2
(-5625 3175);
DISPLAY 1.446809 (-5625 3175);
PAINT GREEN (-5625 3175);
DISPLAY INVISIBLE (-5625 3175);
FORCEPROP 1 LAST PATH I88
J 2
(-5298 3300);
DISPLAY 0.872340 (-5298 3300);
PAINT GREEN (-5298 3300);
DISPLAY INVISIBLE (-5298 3300);
FORCEADD TAP..1
R 2
(-5300 3250);
FORCEPROP 3 LASTPIN (-5250 3250) SIG_NAME P3E_CPU0_PE2_SS_RXN<14>
J 0
(-5240 3260);
DISPLAY 0.659574 (-5240 3260);
PAINT MONO (-5240 3260);
DISPLAY INVISIBLE (-5240 3260);
FORCEPROP 1 LASTPIN (-5250 3250) BN 14
J 2
(-5238 3258);
DISPLAY 0.617021 (-5238 3258);
PAINT PINK (-5238 3258);
FORCEPROP 2 LAST CDS_LIB mstr_standard
J 0
(-5300 3250);
PAINT MONO (-5300 3250);
DISPLAY INVISIBLE (-5300 3250);
FORCEPROP 1 LAST BODY_TYPE PLUMBING
J 2
(-5300 3300);
DISPLAY 1.446809 (-5300 3300);
PAINT GREEN (-5300 3300);
DISPLAY INVISIBLE (-5300 3300);
FORCEPROP 1 LAST HDL_TAP TRUE
J 2
(-5625 3125);
DISPLAY 1.446809 (-5625 3125);
PAINT GREEN (-5625 3125);
DISPLAY INVISIBLE (-5625 3125);
FORCEPROP 1 LAST PATH I89
J 2
(-5298 3250);
DISPLAY 0.872340 (-5298 3250);
PAINT GREEN (-5298 3250);
DISPLAY INVISIBLE (-5298 3250);
FORCEADD TAP..1
R 2
(-5450 2050);
FORCEPROP 3 LASTPIN (-5400 2050) SIG_NAME P3E_CPU0_PE2_SS_RXP<3>
J 0
(-5390 2060);
DISPLAY 0.659574 (-5390 2060);
PAINT MONO (-5390 2060);
DISPLAY INVISIBLE (-5390 2060);
FORCEPROP 1 LASTPIN (-5400 2050) BN 3
J 2
(-5388 2058);
DISPLAY 0.617021 (-5388 2058);
PAINT PINK (-5388 2058);
FORCEPROP 2 LAST CDS_LIB mstr_standard
J 0
(-5450 2050);
PAINT MONO (-5450 2050);
DISPLAY INVISIBLE (-5450 2050);
FORCEPROP 1 LAST BODY_TYPE PLUMBING
J 2
(-5450 2100);
DISPLAY 1.446809 (-5450 2100);
PAINT GREEN (-5450 2100);
DISPLAY INVISIBLE (-5450 2100);
FORCEPROP 1 LAST HDL_TAP TRUE
J 2
(-5775 1925);
DISPLAY 1.446809 (-5775 1925);
PAINT GREEN (-5775 1925);
DISPLAY INVISIBLE (-5775 1925);
FORCEPROP 1 LAST PATH I9
J 2
(-5448 2050);
DISPLAY 0.872340 (-5448 2050);
PAINT GREEN (-5448 2050);
DISPLAY INVISIBLE (-5448 2050);
FORCEADD TAP..1
R 2
(-5300 3200);
FORCEPROP 3 LASTPIN (-5250 3200) SIG_NAME P3E_CPU0_PE2_SS_RXN<13>
J 0
(-5240 3210);
DISPLAY 0.659574 (-5240 3210);
PAINT MONO (-5240 3210);
DISPLAY INVISIBLE (-5240 3210);
FORCEPROP 1 LASTPIN (-5250 3200) BN 13
J 2
(-5238 3208);
DISPLAY 0.617021 (-5238 3208);
PAINT PINK (-5238 3208);
FORCEPROP 2 LAST CDS_LIB mstr_standard
J 0
(-5300 3200);
PAINT MONO (-5300 3200);
DISPLAY INVISIBLE (-5300 3200);
FORCEPROP 1 LAST BODY_TYPE PLUMBING
J 2
(-5300 3250);
DISPLAY 1.446809 (-5300 3250);
PAINT GREEN (-5300 3250);
DISPLAY INVISIBLE (-5300 3250);
FORCEPROP 1 LAST HDL_TAP TRUE
J 2
(-5625 3075);
DISPLAY 1.446809 (-5625 3075);
PAINT GREEN (-5625 3075);
DISPLAY INVISIBLE (-5625 3075);
FORCEPROP 1 LAST PATH I90
J 2
(-5298 3200);
DISPLAY 0.872340 (-5298 3200);
PAINT GREEN (-5298 3200);
DISPLAY INVISIBLE (-5298 3200);
FORCEADD TAP..1
R 2
(-5300 3150);
FORCEPROP 3 LASTPIN (-5250 3150) SIG_NAME P3E_CPU0_PE2_SS_RXN<12>
J 0
(-5240 3160);
DISPLAY 0.659574 (-5240 3160);
PAINT MONO (-5240 3160);
DISPLAY INVISIBLE (-5240 3160);
FORCEPROP 1 LASTPIN (-5250 3150) BN 12
J 2
(-5238 3158);
DISPLAY 0.617021 (-5238 3158);
PAINT PINK (-5238 3158);
FORCEPROP 2 LAST CDS_LIB mstr_standard
J 0
(-5300 3150);
PAINT MONO (-5300 3150);
DISPLAY INVISIBLE (-5300 3150);
FORCEPROP 1 LAST BODY_TYPE PLUMBING
J 2
(-5300 3200);
DISPLAY 1.446809 (-5300 3200);
PAINT GREEN (-5300 3200);
DISPLAY INVISIBLE (-5300 3200);
FORCEPROP 1 LAST HDL_TAP TRUE
J 2
(-5625 3025);
DISPLAY 1.446809 (-5625 3025);
PAINT GREEN (-5625 3025);
DISPLAY INVISIBLE (-5625 3025);
FORCEPROP 1 LAST PATH I91
J 2
(-5298 3150);
DISPLAY 0.872340 (-5298 3150);
PAINT GREEN (-5298 3150);
DISPLAY INVISIBLE (-5298 3150);
FORCEADD TAP..1
R 2
(-5450 3550);
FORCEPROP 3 LASTPIN (-5400 3550) SIG_NAME P3E_CPU0_PE2_SS_RXP<15>
J 0
(-5390 3560);
DISPLAY 0.659574 (-5390 3560);
PAINT MONO (-5390 3560);
DISPLAY INVISIBLE (-5390 3560);
FORCEPROP 1 LASTPIN (-5400 3550) BN 15
J 2
(-5388 3558);
DISPLAY 0.617021 (-5388 3558);
PAINT PINK (-5388 3558);
FORCEPROP 2 LAST CDS_LIB mstr_standard
J 0
(-5450 3550);
PAINT MONO (-5450 3550);
DISPLAY INVISIBLE (-5450 3550);
FORCEPROP 1 LAST BODY_TYPE PLUMBING
J 2
(-5450 3600);
DISPLAY 1.446809 (-5450 3600);
PAINT GREEN (-5450 3600);
DISPLAY INVISIBLE (-5450 3600);
FORCEPROP 1 LAST HDL_TAP TRUE
J 2
(-5775 3425);
DISPLAY 1.446809 (-5775 3425);
PAINT GREEN (-5775 3425);
DISPLAY INVISIBLE (-5775 3425);
FORCEPROP 1 LAST PATH I92
J 2
(-5448 3550);
DISPLAY 0.872340 (-5448 3550);
PAINT GREEN (-5448 3550);
DISPLAY INVISIBLE (-5448 3550);
FORCEADD TAP..1
R 2
(-5450 3500);
FORCEPROP 3 LASTPIN (-5400 3500) SIG_NAME P3E_CPU0_PE2_SS_RXP<14>
J 0
(-5390 3510);
DISPLAY 0.659574 (-5390 3510);
PAINT MONO (-5390 3510);
DISPLAY INVISIBLE (-5390 3510);
FORCEPROP 1 LASTPIN (-5400 3500) BN 14
J 2
(-5388 3508);
DISPLAY 0.617021 (-5388 3508);
PAINT PINK (-5388 3508);
FORCEPROP 2 LAST CDS_LIB mstr_standard
J 0
(-5450 3500);
PAINT MONO (-5450 3500);
DISPLAY INVISIBLE (-5450 3500);
FORCEPROP 1 LAST BODY_TYPE PLUMBING
J 2
(-5450 3550);
DISPLAY 1.446809 (-5450 3550);
PAINT GREEN (-5450 3550);
DISPLAY INVISIBLE (-5450 3550);
FORCEPROP 1 LAST HDL_TAP TRUE
J 2
(-5775 3375);
DISPLAY 1.446809 (-5775 3375);
PAINT GREEN (-5775 3375);
DISPLAY INVISIBLE (-5775 3375);
FORCEPROP 1 LAST PATH I93
J 2
(-5448 3500);
DISPLAY 0.872340 (-5448 3500);
PAINT GREEN (-5448 3500);
DISPLAY INVISIBLE (-5448 3500);
FORCEADD TAP..1
R 2
(-5450 3450);
FORCEPROP 3 LASTPIN (-5400 3450) SIG_NAME P3E_CPU0_PE2_SS_RXP<13>
J 0
(-5390 3460);
DISPLAY 0.659574 (-5390 3460);
PAINT MONO (-5390 3460);
DISPLAY INVISIBLE (-5390 3460);
FORCEPROP 1 LASTPIN (-5400 3450) BN 13
J 2
(-5388 3458);
DISPLAY 0.617021 (-5388 3458);
PAINT PINK (-5388 3458);
FORCEPROP 2 LAST CDS_LIB mstr_standard
J 0
(-5450 3450);
PAINT MONO (-5450 3450);
DISPLAY INVISIBLE (-5450 3450);
FORCEPROP 1 LAST BODY_TYPE PLUMBING
J 2
(-5450 3500);
DISPLAY 1.446809 (-5450 3500);
PAINT GREEN (-5450 3500);
DISPLAY INVISIBLE (-5450 3500);
FORCEPROP 1 LAST HDL_TAP TRUE
J 2
(-5775 3325);
DISPLAY 1.446809 (-5775 3325);
PAINT GREEN (-5775 3325);
DISPLAY INVISIBLE (-5775 3325);
FORCEPROP 1 LAST PATH I94
J 2
(-5448 3450);
DISPLAY 0.872340 (-5448 3450);
PAINT GREEN (-5448 3450);
DISPLAY INVISIBLE (-5448 3450);
FORCEADD TAP..1
R 2
(-5450 3400);
FORCEPROP 3 LASTPIN (-5400 3400) SIG_NAME P3E_CPU0_PE2_SS_RXP<12>
J 0
(-5390 3410);
DISPLAY 0.659574 (-5390 3410);
PAINT MONO (-5390 3410);
DISPLAY INVISIBLE (-5390 3410);
FORCEPROP 1 LASTPIN (-5400 3400) BN 12
J 2
(-5388 3408);
DISPLAY 0.617021 (-5388 3408);
PAINT PINK (-5388 3408);
FORCEPROP 2 LAST CDS_LIB mstr_standard
J 0
(-5450 3400);
PAINT MONO (-5450 3400);
DISPLAY INVISIBLE (-5450 3400);
FORCEPROP 1 LAST BODY_TYPE PLUMBING
J 2
(-5450 3450);
DISPLAY 1.446809 (-5450 3450);
PAINT GREEN (-5450 3450);
DISPLAY INVISIBLE (-5450 3450);
FORCEPROP 1 LAST HDL_TAP TRUE
J 2
(-5775 3275);
DISPLAY 1.446809 (-5775 3275);
PAINT GREEN (-5775 3275);
DISPLAY INVISIBLE (-5775 3275);
FORCEPROP 1 LAST PATH I95
J 2
(-5448 3400);
DISPLAY 0.872340 (-5448 3400);
PAINT GREEN (-5448 3400);
DISPLAY INVISIBLE (-5448 3400);
FORCEADD TAP..1
R 2
(-5450 3050);
FORCEPROP 3 LASTPIN (-5400 3050) SIG_NAME P3E_CPU0_PE2_SS_RXP<11>
J 0
(-5390 3060);
DISPLAY 0.659574 (-5390 3060);
PAINT MONO (-5390 3060);
DISPLAY INVISIBLE (-5390 3060);
FORCEPROP 1 LASTPIN (-5400 3050) BN 11
J 2
(-5388 3058);
DISPLAY 0.617021 (-5388 3058);
PAINT PINK (-5388 3058);
FORCEPROP 2 LAST CDS_LIB mstr_standard
J 0
(-5450 3050);
PAINT MONO (-5450 3050);
DISPLAY INVISIBLE (-5450 3050);
FORCEPROP 1 LAST BODY_TYPE PLUMBING
J 2
(-5450 3100);
DISPLAY 1.446809 (-5450 3100);
PAINT GREEN (-5450 3100);
DISPLAY INVISIBLE (-5450 3100);
FORCEPROP 1 LAST HDL_TAP TRUE
J 2
(-5775 2925);
DISPLAY 1.446809 (-5775 2925);
PAINT GREEN (-5775 2925);
DISPLAY INVISIBLE (-5775 2925);
FORCEPROP 1 LAST PATH I96
J 2
(-5448 3050);
DISPLAY 0.872340 (-5448 3050);
PAINT GREEN (-5448 3050);
DISPLAY INVISIBLE (-5448 3050);
FORCEADD TAP..1
R 2
(-5300 2800);
FORCEPROP 3 LASTPIN (-5250 2800) SIG_NAME P3E_CPU0_PE2_SS_RXN<11>
J 0
(-5240 2810);
DISPLAY 0.659574 (-5240 2810);
PAINT MONO (-5240 2810);
DISPLAY INVISIBLE (-5240 2810);
FORCEPROP 1 LASTPIN (-5250 2800) BN 11
J 2
(-5238 2808);
DISPLAY 0.617021 (-5238 2808);
PAINT PINK (-5238 2808);
FORCEPROP 2 LAST CDS_LIB mstr_standard
J 0
(-5300 2800);
PAINT MONO (-5300 2800);
DISPLAY INVISIBLE (-5300 2800);
FORCEPROP 1 LAST BODY_TYPE PLUMBING
J 2
(-5300 2850);
DISPLAY 1.446809 (-5300 2850);
PAINT GREEN (-5300 2850);
DISPLAY INVISIBLE (-5300 2850);
FORCEPROP 1 LAST HDL_TAP TRUE
J 2
(-5625 2675);
DISPLAY 1.446809 (-5625 2675);
PAINT GREEN (-5625 2675);
DISPLAY INVISIBLE (-5625 2675);
FORCEPROP 1 LAST PATH I97
J 2
(-5298 2800);
DISPLAY 0.872340 (-5298 2800);
PAINT GREEN (-5298 2800);
DISPLAY INVISIBLE (-5298 2800);
FORCEADD TAP..1
R 2
(-5300 2700);
FORCEPROP 3 LASTPIN (-5250 2700) SIG_NAME P3E_CPU0_PE2_SS_RXN<9>
J 0
(-5240 2710);
DISPLAY 0.659574 (-5240 2710);
PAINT MONO (-5240 2710);
DISPLAY INVISIBLE (-5240 2710);
FORCEPROP 1 LASTPIN (-5250 2700) BN 9
J 2
(-5238 2708);
DISPLAY 0.617021 (-5238 2708);
PAINT PINK (-5238 2708);
FORCEPROP 2 LAST CDS_LIB mstr_standard
J 0
(-5300 2700);
PAINT MONO (-5300 2700);
DISPLAY INVISIBLE (-5300 2700);
FORCEPROP 1 LAST BODY_TYPE PLUMBING
J 2
(-5300 2750);
DISPLAY 1.446809 (-5300 2750);
PAINT GREEN (-5300 2750);
DISPLAY INVISIBLE (-5300 2750);
FORCEPROP 1 LAST HDL_TAP TRUE
J 2
(-5625 2575);
DISPLAY 1.446809 (-5625 2575);
PAINT GREEN (-5625 2575);
DISPLAY INVISIBLE (-5625 2575);
FORCEPROP 1 LAST PATH I98
J 2
(-5298 2700);
DISPLAY 0.872340 (-5298 2700);
PAINT GREEN (-5298 2700);
DISPLAY INVISIBLE (-5298 2700);
FORCEADD TAP..1
R 2
(-5300 2750);
FORCEPROP 3 LASTPIN (-5250 2750) SIG_NAME P3E_CPU0_PE2_SS_RXN<10>
J 0
(-5240 2760);
DISPLAY 0.659574 (-5240 2760);
PAINT MONO (-5240 2760);
DISPLAY INVISIBLE (-5240 2760);
FORCEPROP 1 LASTPIN (-5250 2750) BN 10
J 2
(-5238 2758);
DISPLAY 0.617021 (-5238 2758);
PAINT PINK (-5238 2758);
FORCEPROP 2 LAST CDS_LIB mstr_standard
J 0
(-5300 2750);
PAINT MONO (-5300 2750);
DISPLAY INVISIBLE (-5300 2750);
FORCEPROP 1 LAST BODY_TYPE PLUMBING
J 2
(-5300 2800);
DISPLAY 1.446809 (-5300 2800);
PAINT GREEN (-5300 2800);
DISPLAY INVISIBLE (-5300 2800);
FORCEPROP 1 LAST HDL_TAP TRUE
J 2
(-5625 2625);
DISPLAY 1.446809 (-5625 2625);
PAINT GREEN (-5625 2625);
DISPLAY INVISIBLE (-5625 2625);
FORCEPROP 1 LAST PATH I99
J 2
(-5298 2750);
DISPLAY 0.872340 (-5298 2750);
PAINT GREEN (-5298 2750);
DISPLAY INVISIBLE (-5298 2750);
FORCEADD PRELIM..10
(-4015 2590);
PAINT GRAY (-4015 2590);
FORCEPROP 2 LAST CDS_LIB mstr_misc
J 0
(-4015 2590);
PAINT ORANGE (-4015 2590);
DISPLAY INVISIBLE (-4015 2590);
FORCEPROP 1 LAST COMMENT_BODY TRUE
J 0
(-4015 2590);
PAINT ORANGE (-4015 2590);
DISPLAY INVISIBLE (-4015 2590);
FORCEADD DESIGN_NOTE..1
(-4550 1325);
FORCEPROP 0 LAST L1 CPU SYMBOLS 1-30 ARE PRELIMINARY AND SUBJECT TO CHANGE
J 0
(-4750 1200);
DISPLAY 1.021277 (-4750 1200);
PAINT ORANGE (-4750 1200);
FORCEPROP 2 LAST CDS_LIB mstr_symbols
J 0
(-4550 1325);
PAINT ORANGE (-4550 1325);
DISPLAY INVISIBLE (-4550 1325);
FORCEPROP 1 LAST COMMENT_BODY TRUE
J 0
(-4525 1425);
DISPLAY 0.978723 (-4525 1425);
PAINT ORANGE (-4525 1425);
DISPLAY INVISIBLE (-4525 1425);
FORCEADD INTEL_CORP_BPAGE..1
(0 0);
FORCEPROP 1 LAST CDS_CON_LAST_MODIFIED Tue Dec 01 11:51:20 2015
J 0
(-1425 325);
DISPLAY 1.340426 (-1425 325);
PAINT GREEN (-1425 325);
DISPLAY INVISIBLE (-1425 325);
FORCEPROP 1 LAST CUSTOM_TXT_CDS <CURRENT_DESIGN_SHEET> OF <TOTAL_DESIGN_SHEETS>
J 0
(-500 25);
PAINT GREEN (-500 25);
FORCEPROP 1 LAST CUSTOM_TXT_CDS <CON_LAST_MODIFIED>
J 0
(-1925 350);
PAINT GREEN (-1925 350);
FORCEPROP 2 LAST CUSTOM_TXT_CDS <XR_PAGE_TITLE>
J 0
(-7890 5250);
DISPLAY 0.638298 (-7890 5250);
PAINT PINK (-7890 5250);
DISPLAY INVISIBLE (-7890 5250);
FORCEPROP 1 LAST SCH_ADDRESS3 Santa Clara, CA 95052-8119
J 0
(-3975 25);
DISPLAY 0.617021 (-3975 25);
PAINT GREEN (-3975 25);
FORCEPROP 1 LAST SCH_ADDRESS2 P.O. BOX 58119
J 0
(-3975 75);
DISPLAY 0.617021 (-3975 75);
PAINT GREEN (-3975 75);
FORCEPROP 1 LAST SCH_ADDRESS1 2200 Mission College Blvd.
J 0
(-3975 125);
DISPLAY 0.617021 (-3975 125);
PAINT GREEN (-3975 125);
FORCEPROP 1 LAST SCH_TITLE SKYLAKE - SKT0 - 11 OF 21
J 0
(-7950 50);
DISPLAY 1.212766 (-7950 50);
PAINT GREEN (-7950 50);
FORCEPROP 1 LAST SCH_NUMBER H4694802
J 0
(-1300 150);
DISPLAY 1.212766 (-1300 150);
PAINT YELLOW (-1300 150);
FORCEPROP 1 LAST SCH_DEPT BESD
J 1
(-4450 100);
DISPLAY 1.212766 (-4450 100);
PAINT YELLOW (-4450 100);
FORCEPROP 1 LAST SCH_REV 2.420
J 0
(-250 150);
DISPLAY 0.978723 (-250 150);
PAINT YELLOW (-250 150);
FORCEPROP 2 LAST PAGE_BORDER TRUE
J 0
(-7890 5250);
DISPLAY 0.851064 (-7890 5250);
PAINT PINK (-7890 5250);
DISPLAY INVISIBLE (-7890 5250);
FORCEPROP 2 LAST CDS_LIB mstr_symbols
J 0
(0 0);
PAINT ORANGE (0 0);
DISPLAY INVISIBLE (0 0);
FORCEPROP 1 LAST COMMENT_BODY TRUE
J 0
(12 12);
DISPLAY 0.638298 (12 12);
PAINT GREEN (12 12);
DISPLAY INVISIBLE (12 12);
FORCEPROP 2 LAST CDS_XR_PAGE_TITLE CR-31 : @BASEBOARD_FAB2_LIB.BASEBOARD_FAB2(SCH_1):PAGE31
J 0
(-7890 5250);
DISPLAY 0.638298 (-7890 5250);
PAINT PINK (-7890 5250);
DISPLAY INVISIBLE (-7890 5250);
WIRE 17 -1 (-2625 3275)(-2625 3325);
WIRE 17 -1 (-2625 3225)(-2625 3275);
WIRE 17 -1 (-2625 3575)(-2625 3325);
WIRE 17 -1 (-2625 3575)(-1775 3575);
FORCEPROP 2 LAST SIG_NAME P3E_CPU0_PE2_SS_TXN<15:0>
J 0
(-2525 3585);
DISPLAY 0.617021 (-2525 3585);
PAINT ORANGE (-2525 3585);
WIRE 17 -1 (-2625 3175)(-2625 3225);
WIRE 17 -1 (-2625 3175)(-2625 2825);
WIRE 17 -1 (-2625 2775)(-2625 2825);
WIRE 17 -1 (-2625 2725)(-2625 2775);
WIRE 17 -1 (-2625 2675)(-2625 2725);
WIRE 17 -1 (-2625 2325)(-2625 2675);
WIRE 17 -1 (-2625 2275)(-2625 2325);
WIRE 17 -1 (-2625 2225)(-2625 2275);
WIRE 17 -1 (-2625 2175)(-2625 2225);
WIRE 17 -1 (-2625 2175)(-2625 1825);
WIRE 17 -1 (-2625 1775)(-2625 1825);
WIRE 17 -1 (-2625 1725)(-2625 1775);
WIRE 17 -1 (-2625 1675)(-2625 1725);
WIRE 17 -1 (-2775 3525)(-2775 3575);
WIRE 17 -1 (-2775 3475)(-2775 3525);
WIRE 17 -1 (-2775 3625)(-2775 3575);
WIRE 17 -1 (-2775 3625)(-1775 3625);
FORCEPROP 2 LAST SIG_NAME P3E_CPU0_PE2_SS_TXP<15:0>
J 0
(-2525 3635);
DISPLAY 0.617021 (-2525 3635);
PAINT ORANGE (-2525 3635);
WIRE 17 -1 (-2775 3425)(-2775 3475);
WIRE 17 -1 (-2775 3425)(-2775 3075);
WIRE 17 -1 (-2775 3075)(-2775 3025);
WIRE 17 -1 (-2775 2975)(-2775 3025);
WIRE 17 -1 (-2775 2925)(-2775 2975);
WIRE 17 -1 (-2775 2925)(-2775 2575);
WIRE 17 -1 (-2775 2525)(-2775 2575);
WIRE 17 -1 (-2775 2475)(-2775 2525);
WIRE 17 -1 (-2775 2425)(-2775 2475);
WIRE 17 -1 (-2775 2075)(-2775 2425);
WIRE 17 -1 (-2775 2025)(-2775 2075);
WIRE 17 -1 (-2775 1975)(-2775 2025);
WIRE 17 -1 (-2775 1925)(-2775 1975);
WIRE 17 -1 (-5350 3650)(-5350 3325);
WIRE 17 -1 (-6550 3650)(-5350 3650);
FORCEPROP 2 LAST SIG_NAME P3E_CPU0_PE2_SS_RXN<15:0>
J 0
(-6535 3660);
DISPLAY 0.617021 (-6535 3660);
PAINT ORANGE (-6535 3660);
WIRE 17 -1 (-5350 3325)(-5350 3275);
WIRE 17 -1 (-5350 3275)(-5350 3225);
WIRE 17 -1 (-5350 3225)(-5350 3175);
WIRE 17 -1 (-5350 3175)(-5350 2825);
WIRE 17 -1 (-5350 2775)(-5350 2825);
WIRE 17 -1 (-5350 2725)(-5350 2775);
WIRE 17 -1 (-5350 2725)(-5350 2675);
WIRE 17 -1 (-5350 2325)(-5350 2675);
WIRE 17 -1 (-5350 2325)(-5350 2275);
WIRE 17 -1 (-5350 2275)(-5350 2225);
WIRE 17 -1 (-5350 2225)(-5350 2175);
WIRE 17 -1 (-5350 2175)(-5350 1825);
WIRE 17 -1 (-5350 1775)(-5350 1825);
WIRE 17 -1 (-5350 1725)(-5350 1775);
WIRE 17 -1 (-5350 1725)(-5350 1675);
WIRE 17 -1 (-5500 3700)(-5500 3575);
WIRE 17 -1 (-6550 3700)(-5500 3700);
FORCEPROP 2 LAST SIG_NAME P3E_CPU0_PE2_SS_RXP<15:0>
J 0
(-6535 3710);
DISPLAY 0.617021 (-6535 3710);
PAINT ORANGE (-6535 3710);
WIRE 17 -1 (-5500 3575)(-5500 3525);
WIRE 17 -1 (-5500 3525)(-5500 3475);
WIRE 17 -1 (-5500 3475)(-5500 3425);
WIRE 17 -1 (-5500 3425)(-5500 3075);
WIRE 17 -1 (-5500 3075)(-5500 3025);
WIRE 17 -1 (-5500 3025)(-5500 2975);
WIRE 17 -1 (-5500 2925)(-5500 2975);
WIRE 17 -1 (-5500 2575)(-5500 2925);
WIRE 17 -1 (-5500 2575)(-5500 2525);
WIRE 17 -1 (-5500 2525)(-5500 2475);
WIRE 17 -1 (-5500 2475)(-5500 2425);
WIRE 17 -1 (-5500 2425)(-5500 2075);
WIRE 17 -1 (-5500 2075)(-5500 2025);
WIRE 17 -1 (-5500 2025)(-5500 1975);
WIRE 17 -1 (-5500 1925)(-5500 1975);
WIRE 16 -1 (-4775 1750)(-5250 1750);
WIRE 16 -1 (-4775 1900)(-5400 1900);
WIRE 16 -1 (-5400 1950)(-4775 1950);
WIRE 16 -1 (-4775 2000)(-5400 2000);
WIRE 16 -1 (-4775 1650)(-5250 1650);
WIRE 16 -1 (-4775 1700)(-5250 1700);
WIRE 16 -1 (-5250 1800)(-4775 1800);
WIRE 16 -1 (-5400 2050)(-4775 2050);
WIRE 16 -1 (-4775 2400)(-5400 2400);
WIRE 16 -1 (-5400 2450)(-4775 2450);
WIRE 16 -1 (-4775 2500)(-5400 2500);
WIRE 16 -1 (-5400 2550)(-4775 2550);
WIRE 16 -1 (-4775 2900)(-5400 2900);
WIRE 16 -1 (-5400 2950)(-4775 2950);
WIRE 16 -1 (-4775 3000)(-5400 3000);
WIRE 16 -1 (-5400 3050)(-4775 3050);
WIRE 16 -1 (-4775 3400)(-5400 3400);
WIRE 16 -1 (-5400 3450)(-4775 3450);
WIRE 16 -1 (-4775 3500)(-5400 3500);
WIRE 16 -1 (-5400 3550)(-4775 3550);
WIRE 16 -1 (-4775 2150)(-5250 2150);
WIRE 16 -1 (-5250 2200)(-4775 2200);
WIRE 16 -1 (-4775 2250)(-5250 2250);
WIRE 16 -1 (-5250 2300)(-4775 2300);
WIRE 16 -1 (-4775 2650)(-5250 2650);
WIRE 16 -1 (-4775 2700)(-5250 2700);
WIRE 16 -1 (-4775 2750)(-5250 2750);
WIRE 16 -1 (-5250 2800)(-4775 2800);
WIRE 16 -1 (-4775 3150)(-5250 3150);
WIRE 16 -1 (-5250 3200)(-4775 3200);
WIRE 16 -1 (-4775 3250)(-5250 3250);
WIRE 16 -1 (-5250 3300)(-4775 3300);
WIRE 16 -1 (-2875 1900)(-3275 1900);
WIRE 16 -1 (-3275 1950)(-2875 1950);
WIRE 16 -1 (-3275 2000)(-2875 2000);
WIRE 16 -1 (-2725 1650)(-3275 1650);
WIRE 16 -1 (-3275 1700)(-2725 1700);
WIRE 16 -1 (-2725 1750)(-3275 1750);
WIRE 16 -1 (-3275 1800)(-2725 1800);
WIRE 16 -1 (-2875 2050)(-3275 2050);
WIRE 16 -1 (-2875 2400)(-3275 2400);
WIRE 16 -1 (-2875 2450)(-3275 2450);
WIRE 16 -1 (-2875 2500)(-3275 2500);
WIRE 16 -1 (-2875 2550)(-3275 2550);
WIRE 16 -1 (-2875 2900)(-3275 2900);
WIRE 16 -1 (-3275 2950)(-2875 2950);
WIRE 16 -1 (-3275 3000)(-2875 3000);
WIRE 16 -1 (-3275 3050)(-2875 3050);
WIRE 16 -1 (-2875 3400)(-3275 3400);
WIRE 16 -1 (-2875 3450)(-3275 3450);
WIRE 16 -1 (-2875 3500)(-3275 3500);
WIRE 16 -1 (-2875 3550)(-3275 3550);
WIRE 16 -1 (-2725 2150)(-3275 2150);
WIRE 16 -1 (-2725 2200)(-3275 2200);
WIRE 16 -1 (-3275 2250)(-2725 2250);
WIRE 16 -1 (-3275 2300)(-2725 2300);
WIRE 16 -1 (-3275 2650)(-2725 2650);
WIRE 16 -1 (-2725 2700)(-3275 2700);
WIRE 16 -1 (-3275 2750)(-2725 2750);
WIRE 16 -1 (-3275 2800)(-2725 2800);
WIRE 16 -1 (-3275 3150)(-2725 3150);
WIRE 16 -1 (-3275 3200)(-2725 3200);
WIRE 16 -1 (-2725 3250)(-3275 3250);
WIRE 16 -1 (-2725 3300)(-3275 3300);
FORCENOTE
BOM_COST=PROC_SOCKET
(-7925 225) 0;
DISPLAY LEFT (-7925 225);
DISPLAY 1.723404 (-7925 225);
PAINT PURPLE (-7925 225);
FORCENOTE
ROOM=CPU0
(-7925 350) 0;
DISPLAY LEFT (-7925 350);
DISPLAY 1.723404 (-7925 350);
PAINT PURPLE (-7925 350);
FORCENOTE
FROM X24 SUPER SLOT
(-6700 3500) 0;
DISPLAY LEFT (-6700 3500);
DISPLAY 1.021277 (-6700 3500);
PAINT PURPLE (-6700 3500);
FORCENOTE
TO X24 SUPER SLOT
(-2225 3425) 0;
DISPLAY LEFT (-2225 3425);
DISPLAY 1.021277 (-2225 3425);
PAINT PURPLE (-2225 3425);
QUIT
